G04 ================== begin FILE IDENTIFICATION RECORD ==================*
G04 Layout Name:  13948-1b.brd*
G04 Film Name:    BMASK*
G04 File Format:  Gerber RS274X*
G04 File Origin:  Cadence Allegro 16.5-S045*
G04 Origin Date:  Thu Nov 13 15:45:45 2014*
G04 *
G04 Layer:  VIA CLASS/SOLDERMASK_BOTTOM*
G04 Layer:  PIN/SOLDERMASK_BOTTOM*
G04 Layer:  PACKAGE GEOMETRY/SOLDERMASK_BOTTOM*
G04 Layer:  DRAWING FORMAT/LAYER_PCB_STORY*
G04 Layer:  DRAWING FORMAT/LAYER_SOLDER_B*
G04 Layer:  BOARD GEOMETRY/SOLDERMASK_BOTTOM*
G04 *
G04 Offset:    (0.00 0.00)*
G04 Mirror:    No*
G04 Mode:      Positive*
G04 Rotation:  0*
G04 FullContactRelief:  No*
G04 UndefLineWidth:     6.00*
G04 ================== end FILE IDENTIFICATION RECORD ====================*
%FSLAX35Y35*MOIN*%
%IR0*IPPOS*OFA0.00000B0.00000*MIA0B0*SFA1.00000B1.00000*%
%AMMACRO20*
4,1,40,.011,.007,
.011,-.007,
.010939,-.007695,
.010759,-.008368,
.010464,-.009,
.010064,-.009571,
.009571,-.010064,
.009,-.010464,
.008368,-.010759,
.007695,-.010939,
.007,-.011,
-.007,-.011,
-.007695,-.010939,
-.008368,-.010759,
-.009,-.010464,
-.009571,-.010064,
-.010064,-.009571,
-.010464,-.009,
-.010759,-.008368,
-.010939,-.007695,
-.011,-.007,
-.011,.007,
-.010939,.007695,
-.010759,.008368,
-.010464,.009,
-.010064,.009571,
-.009571,.010064,
-.009,.010464,
-.008368,.010759,
-.007695,.010939,
-.007,.011,
.007,.011,
.007695,.010939,
.008368,.010759,
.009,.010464,
.009571,.010064,
.010064,.009571,
.010464,.009,
.010759,.008368,
.010939,.007695,
.011,.007,
0.0*
%
%ADD20MACRO20*%
%AMMACRO70*
4,1,40,.013,-.017,
-.013,-.017,
-.013695,-.016939,
-.014368,-.016759,
-.015,-.016464,
-.015571,-.016064,
-.016064,-.015571,
-.016464,-.015,
-.016759,-.014368,
-.016939,-.013695,
-.017,-.013,
-.017,.013,
-.016939,.013695,
-.016759,.014368,
-.016464,.015,
-.016064,.015571,
-.015571,.016064,
-.015,.016464,
-.014368,.016759,
-.013695,.016939,
-.013,.017,
.013,.017,
.013695,.016939,
.014368,.016759,
.015,.016464,
.015571,.016064,
.016064,.015571,
.016464,.015,
.016759,.014368,
.016939,.013695,
.017,.013,
.017,-.013,
.016939,-.013695,
.016759,-.014368,
.016464,-.015,
.016064,-.015571,
.015571,-.016064,
.015,-.016464,
.014368,-.016759,
.013695,-.016939,
.013,-.017,
0.0*
%
%ADD70MACRO70*%
%AMMACRO35*
4,1,40,-.017,-.013,
-.017,.013,
-.016939,.013695,
-.016759,.014368,
-.016464,.015,
-.016064,.015571,
-.015571,.016064,
-.015,.016464,
-.014368,.016759,
-.013695,.016939,
-.013,.017,
.013,.017,
.013695,.016939,
.014368,.016759,
.015,.016464,
.015571,.016064,
.016064,.015571,
.016464,.015,
.016759,.014368,
.016939,.013695,
.017,.013,
.017,-.013,
.016939,-.013695,
.016759,-.014368,
.016464,-.015,
.016064,-.015571,
.015571,-.016064,
.015,-.016464,
.014368,-.016759,
.013695,-.016939,
.013,-.017,
-.013,-.017,
-.013695,-.016939,
-.014368,-.016759,
-.015,-.016464,
-.015571,-.016064,
-.016064,-.015571,
-.016464,-.015,
-.016759,-.014368,
-.016939,-.013695,
-.017,-.013,
0.0*
%
%ADD35MACRO35*%
%ADD71C,.04*%
%ADD58C,.022*%
%ADD29C,.032*%
%ADD27C,.05*%
%AMMACRO48*
4,1,40,-.007,-.004,
-.007,.004,
-.00697,.004347,
-.006879,.004684,
-.006732,.005,
-.006532,.005286,
-.006286,.005532,
-.006,.005732,
-.005684,.005879,
-.005347,.00597,
-.005,.006,
.005,.006,
.005347,.00597,
.005684,.005879,
.006,.005732,
.006286,.005532,
.006532,.005286,
.006732,.005,
.006879,.004684,
.00697,.004347,
.007,.004,
.007,-.004,
.00697,-.004347,
.006879,-.004684,
.006732,-.005,
.006532,-.005286,
.006286,-.005532,
.006,-.005732,
.005684,-.005879,
.005347,-.00597,
.005,-.006,
-.005,-.006,
-.005347,-.00597,
-.005684,-.005879,
-.006,-.005732,
-.006286,-.005532,
-.006532,-.005286,
-.006732,-.005,
-.006879,-.004684,
-.00697,-.004347,
-.007,-.004,
0.0*
%
%ADD48MACRO48*%
%ADD31R,.028X.126*%
%ADD78C,.016*%
%ADD77C,.034*%
%ADD65C,.052*%
%ADD61C,.043*%
%AMMACRO51*
4,1,40,-.004,.007,
.004,.007,
.004347,.00697,
.004684,.006879,
.005,.006732,
.005286,.006532,
.005532,.006286,
.005732,.006,
.005879,.005684,
.00597,.005347,
.006,.005,
.006,-.005,
.00597,-.005347,
.005879,-.005684,
.005732,-.006,
.005532,-.006286,
.005286,-.006532,
.005,-.006732,
.004684,-.006879,
.004347,-.00697,
.004,-.007,
-.004,-.007,
-.004347,-.00697,
-.004684,-.006879,
-.005,-.006732,
-.005286,-.006532,
-.005532,-.006286,
-.005732,-.006,
-.005879,-.005684,
-.00597,-.005347,
-.006,-.005,
-.006,.005,
-.00597,.005347,
-.005879,.005684,
-.005732,.006,
-.005532,.006286,
-.005286,.006532,
-.005,.006732,
-.004684,.006879,
-.004347,.00697,
-.004,.007,
0.0*
%
%ADD51MACRO51*%
%ADD13C,.061*%
%ADD21C,.08*%
%ADD11C,.062*%
%ADD75C,.054*%
%ADD53C,.045*%
%ADD26R,.028X.165*%
%ADD28C,.046*%
%ADD14C,.028*%
%ADD80C,.038*%
%ADD30C,.056*%
%ADD76C,.048*%
%ADD62C,.066*%
%ADD60C,.093*%
%ADD79C,.058*%
%ADD57R,.297X.081*%
%ADD12C,.086*%
%ADD63C,.078*%
%AMMACRO36*
4,1,40,.0225,.007,
.022378,.008389,
.022018,.009736,
.021428,.011,
.020628,.012142,
.019642,.013128,
.0185,.013928,
.017236,.014518,
.015889,.014878,
.0145,.015,
-.0145,.015,
-.015889,.014878,
-.017236,.014518,
-.0185,.013928,
-.019642,.013128,
-.020628,.012142,
-.021428,.011,
-.022018,.009736,
-.022378,.008389,
-.0225,.007,
-.0225,-.007,
-.022378,-.008389,
-.022018,-.009736,
-.021428,-.011,
-.020628,-.012142,
-.019642,-.013128,
-.0185,-.013928,
-.017236,-.014518,
-.015889,-.014878,
-.0145,-.015,
.0145,-.015,
.015889,-.014878,
.017236,-.014518,
.0185,-.013928,
.019642,-.013128,
.020628,-.012142,
.021428,-.011,
.022018,-.009736,
.022378,-.008389,
.0225,-.007,
.0225,.007,
0.0*
%
%ADD36MACRO36*%
%AMMACRO66*
4,1,40,.007,-.0225,
.008389,-.022378,
.009736,-.022018,
.011,-.021428,
.012142,-.020628,
.013128,-.019642,
.013928,-.0185,
.014518,-.017236,
.014878,-.015889,
.015,-.0145,
.015,.0145,
.014878,.015889,
.014518,.017236,
.013928,.0185,
.013128,.019642,
.012142,.020628,
.011,.021428,
.009736,.022018,
.008389,.022378,
.007,.0225,
-.007,.0225,
-.008389,.022378,
-.009736,.022018,
-.011,.021428,
-.012142,.020628,
-.013128,.019642,
-.013928,.0185,
-.014518,.017236,
-.014878,.015889,
-.015,.0145,
-.015,-.0145,
-.014878,-.015889,
-.014518,-.017236,
-.013928,-.0185,
-.013128,-.019642,
-.012142,-.020628,
-.011,-.021428,
-.009736,-.022018,
-.008389,-.022378,
-.007,-.0225,
.007,-.0225,
0.0*
%
%ADD66MACRO66*%
%AMMACRO42*
4,1,40,-.011,-.007,
-.011,.007,
-.010939,.007695,
-.010759,.008368,
-.010464,.009,
-.010064,.009571,
-.009571,.010064,
-.009,.010464,
-.008368,.010759,
-.007695,.010939,
-.007,.011,
.007,.011,
.007695,.010939,
.008368,.010759,
.009,.010464,
.009571,.010064,
.010064,.009571,
.010464,.009,
.010759,.008368,
.010939,.007695,
.011,.007,
.011,-.007,
.010939,-.007695,
.010759,-.008368,
.010464,-.009,
.010064,-.009571,
.009571,-.010064,
.009,-.010464,
.008368,-.010759,
.007695,-.010939,
.007,-.011,
-.007,-.011,
-.007695,-.010939,
-.008368,-.010759,
-.009,-.010464,
-.009571,-.010064,
-.010064,-.009571,
-.010464,-.009,
-.010759,-.008368,
-.010939,-.007695,
-.011,-.007,
0.0*
%
%ADD42MACRO42*%
%AMMACRO34*
4,1,40,.007,-.011,
-.007,-.011,
-.007695,-.010939,
-.008368,-.010759,
-.009,-.010464,
-.009571,-.010064,
-.010064,-.009571,
-.010464,-.009,
-.010759,-.008368,
-.010939,-.007695,
-.011,-.007,
-.011,.007,
-.010939,.007695,
-.010759,.008368,
-.010464,.009,
-.010064,.009571,
-.009571,.010064,
-.009,.010464,
-.008368,.010759,
-.007695,.010939,
-.007,.011,
.007,.011,
.007695,.010939,
.008368,.010759,
.009,.010464,
.009571,.010064,
.010064,.009571,
.010464,.009,
.010759,.008368,
.010939,.007695,
.011,.007,
.011,-.007,
.010939,-.007695,
.010759,-.008368,
.010464,-.009,
.010064,-.009571,
.009571,-.010064,
.009,-.010464,
.008368,-.010759,
.007695,-.010939,
.007,-.011,
0.0*
%
%ADD34MACRO34*%
%AMMACRO23*
4,1,40,-.012,-.008,
-.012,.008,
-.011939,.008695,
-.011759,.009368,
-.011464,.01,
-.011064,.010571,
-.010571,.011064,
-.01,.011464,
-.009368,.011759,
-.008695,.011939,
-.008,.012,
.008,.012,
.008695,.011939,
.009368,.011759,
.01,.011464,
.010571,.011064,
.011064,.010571,
.011464,.01,
.011759,.009368,
.011939,.008695,
.012,.008,
.012,-.008,
.011939,-.008695,
.011759,-.009368,
.011464,-.01,
.011064,-.010571,
.010571,-.011064,
.01,-.011464,
.009368,-.011759,
.008695,-.011939,
.008,-.012,
-.008,-.012,
-.008695,-.011939,
-.009368,-.011759,
-.01,-.011464,
-.010571,-.011064,
-.011064,-.010571,
-.011464,-.01,
-.011759,-.009368,
-.011939,-.008695,
-.012,-.008,
0.0*
%
%ADD23MACRO23*%
%AMMACRO16*
4,1,40,-.008,.012,
.008,.012,
.008695,.011939,
.009368,.011759,
.01,.011464,
.010571,.011064,
.011064,.010571,
.011464,.01,
.011759,.009368,
.011939,.008695,
.012,.008,
.012,-.008,
.011939,-.008695,
.011759,-.009368,
.011464,-.01,
.011064,-.010571,
.010571,-.011064,
.01,-.011464,
.009368,-.011759,
.008695,-.011939,
.008,-.012,
-.008,-.012,
-.008695,-.011939,
-.009368,-.011759,
-.01,-.011464,
-.010571,-.011064,
-.011064,-.010571,
-.011464,-.01,
-.011759,-.009368,
-.011939,-.008695,
-.012,-.008,
-.012,.008,
-.011939,.008695,
-.011759,.009368,
-.011464,.01,
-.011064,.010571,
-.010571,.011064,
-.01,.011464,
-.009368,.011759,
-.008695,.011939,
-.008,.012,
0.0*
%
%ADD16MACRO16*%
%AMMACRO67*
4,1,40,-.013,.017,
.013,.017,
.013695,.016939,
.014368,.016759,
.015,.016464,
.015571,.016064,
.016064,.015571,
.016464,.015,
.016759,.014368,
.016939,.013695,
.017,.013,
.017,-.013,
.016939,-.013695,
.016759,-.014368,
.016464,-.015,
.016064,-.015571,
.015571,-.016064,
.015,-.016464,
.014368,-.016759,
.013695,-.016939,
.013,-.017,
-.013,-.017,
-.013695,-.016939,
-.014368,-.016759,
-.015,-.016464,
-.015571,-.016064,
-.016064,-.015571,
-.016464,-.015,
-.016759,-.014368,
-.016939,-.013695,
-.017,-.013,
-.017,.013,
-.016939,.013695,
-.016759,.014368,
-.016464,.015,
-.016064,.015571,
-.015571,.016064,
-.015,.016464,
-.014368,.016759,
-.013695,.016939,
-.013,.017,
0.0*
%
%ADD67MACRO67*%
%AMMACRO82*
4,1,6,.025,-.0135,
.005,.0065,
.005,.0135,
-.005,.0135,
-.005,.0065,
-.025,-.0135,
.025,-.0135,
0.0*
%
%ADD82MACRO82*%
%AMMACRO49*
4,1,40,.017,.013,
.017,-.013,
.016939,-.013695,
.016759,-.014368,
.016464,-.015,
.016064,-.015571,
.015571,-.016064,
.015,-.016464,
.014368,-.016759,
.013695,-.016939,
.013,-.017,
-.013,-.017,
-.013695,-.016939,
-.014368,-.016759,
-.015,-.016464,
-.015571,-.016064,
-.016064,-.015571,
-.016464,-.015,
-.016759,-.014368,
-.016939,-.013695,
-.017,-.013,
-.017,.013,
-.016939,.013695,
-.016759,.014368,
-.016464,.015,
-.016064,.015571,
-.015571,.016064,
-.015,.016464,
-.014368,.016759,
-.013695,.016939,
-.013,.017,
.013,.017,
.013695,.016939,
.014368,.016759,
.015,.016464,
.015571,.016064,
.016064,.015571,
.016464,.015,
.016759,.014368,
.016939,.013695,
.017,.013,
0.0*
%
%ADD49MACRO49*%
%AMMACRO43*
4,1,40,-.011,-.007,
-.011,.007,
-.010939,.007695,
-.010759,.008368,
-.010464,.009,
-.010064,.009571,
-.009571,.010064,
-.009,.010464,
-.008368,.010759,
-.007695,.010939,
-.007,.011,
.007,.011,
.007695,.010939,
.008368,.010759,
.009,.010464,
.009571,.010064,
.010064,.009571,
.010464,.009,
.010759,.008368,
.010939,.007695,
.011,.007,
.011,-.007,
.010939,-.007695,
.010759,-.008368,
.010464,-.009,
.010064,-.009571,
.009571,-.010064,
.009,-.010464,
.008368,-.010759,
.007695,-.010939,
.007,-.011,
-.007,-.011,
-.007695,-.010939,
-.008368,-.010759,
-.009,-.010464,
-.009571,-.010064,
-.010064,-.009571,
-.010464,-.009,
-.010759,-.008368,
-.010939,-.007695,
-.011,-.007,
0.0*
%
%ADD43MACRO43*%
%AMMACRO38*
4,1,40,.007,-.011,
-.007,-.011,
-.007695,-.010939,
-.008368,-.010759,
-.009,-.010464,
-.009571,-.010064,
-.010064,-.009571,
-.010464,-.009,
-.010759,-.008368,
-.010939,-.007695,
-.011,-.007,
-.011,.007,
-.010939,.007695,
-.010759,.008368,
-.010464,.009,
-.010064,.009571,
-.009571,.010064,
-.009,.010464,
-.008368,.010759,
-.007695,.010939,
-.007,.011,
.007,.011,
.007695,.010939,
.008368,.010759,
.009,.010464,
.009571,.010064,
.010064,.009571,
.010464,.009,
.010759,.008368,
.010939,.007695,
.011,.007,
.011,-.007,
.010939,-.007695,
.010759,-.008368,
.010464,-.009,
.010064,-.009571,
.009571,-.010064,
.009,-.010464,
.008368,-.010759,
.007695,-.010939,
.007,-.011,
0.0*
%
%ADD38MACRO38*%
%AMMACRO22*
4,1,40,-.012,-.008,
-.012,.008,
-.011939,.008695,
-.011759,.009368,
-.011464,.01,
-.011064,.010571,
-.010571,.011064,
-.01,.011464,
-.009368,.011759,
-.008695,.011939,
-.008,.012,
.008,.012,
.008695,.011939,
.009368,.011759,
.01,.011464,
.010571,.011064,
.011064,.010571,
.011464,.01,
.011759,.009368,
.011939,.008695,
.012,.008,
.012,-.008,
.011939,-.008695,
.011759,-.009368,
.011464,-.01,
.011064,-.010571,
.010571,-.011064,
.01,-.011464,
.009368,-.011759,
.008695,-.011939,
.008,-.012,
-.008,-.012,
-.008695,-.011939,
-.009368,-.011759,
-.01,-.011464,
-.010571,-.011064,
-.011064,-.010571,
-.011464,-.01,
-.011759,-.009368,
-.011939,-.008695,
-.012,-.008,
0.0*
%
%ADD22MACRO22*%
%AMMACRO15*
4,1,40,-.008,.012,
.008,.012,
.008695,.011939,
.009368,.011759,
.01,.011464,
.010571,.011064,
.011064,.010571,
.011464,.01,
.011759,.009368,
.011939,.008695,
.012,.008,
.012,-.008,
.011939,-.008695,
.011759,-.009368,
.011464,-.01,
.011064,-.010571,
.010571,-.011064,
.01,-.011464,
.009368,-.011759,
.008695,-.011939,
.008,-.012,
-.008,-.012,
-.008695,-.011939,
-.009368,-.011759,
-.01,-.011464,
-.010571,-.011064,
-.011064,-.010571,
-.011464,-.01,
-.011759,-.009368,
-.011939,-.008695,
-.012,-.008,
-.012,.008,
-.011939,.008695,
-.011759,.009368,
-.011464,.01,
-.011064,.010571,
-.010571,.011064,
-.01,.011464,
-.009368,.011759,
-.008695,.011939,
-.008,.012,
0.0*
%
%ADD15MACRO15*%
%AMMACRO68*
4,1,40,-.013,.017,
.013,.017,
.013695,.016939,
.014368,.016759,
.015,.016464,
.015571,.016064,
.016064,.015571,
.016464,.015,
.016759,.014368,
.016939,.013695,
.017,.013,
.017,-.013,
.016939,-.013695,
.016759,-.014368,
.016464,-.015,
.016064,-.015571,
.015571,-.016064,
.015,-.016464,
.014368,-.016759,
.013695,-.016939,
.013,-.017,
-.013,-.017,
-.013695,-.016939,
-.014368,-.016759,
-.015,-.016464,
-.015571,-.016064,
-.016064,-.015571,
-.016464,-.015,
-.016759,-.014368,
-.016939,-.013695,
-.017,-.013,
-.017,.013,
-.016939,.013695,
-.016759,.014368,
-.016464,.015,
-.016064,.015571,
-.015571,.016064,
-.015,.016464,
-.014368,.016759,
-.013695,.016939,
-.013,.017,
0.0*
%
%ADD68MACRO68*%
%AMMACRO50*
4,1,40,.017,.013,
.017,-.013,
.016939,-.013695,
.016759,-.014368,
.016464,-.015,
.016064,-.015571,
.015571,-.016064,
.015,-.016464,
.014368,-.016759,
.013695,-.016939,
.013,-.017,
-.013,-.017,
-.013695,-.016939,
-.014368,-.016759,
-.015,-.016464,
-.015571,-.016064,
-.016064,-.015571,
-.016464,-.015,
-.016759,-.014368,
-.016939,-.013695,
-.017,-.013,
-.017,.013,
-.016939,.013695,
-.016759,.014368,
-.016464,.015,
-.016064,.015571,
-.015571,.016064,
-.015,.016464,
-.014368,.016759,
-.013695,.016939,
-.013,.017,
.013,.017,
.013695,.016939,
.014368,.016759,
.015,.016464,
.015571,.016064,
.016064,.015571,
.016464,.015,
.016759,.014368,
.016939,.013695,
.017,.013,
0.0*
%
%ADD50MACRO50*%
%ADD73R,.02X.06*%
%ADD56R,.012X.038*%
%ADD55R,.038X.012*%
%AMMACRO52*
4,1,40,.004,-.007,
-.004,-.007,
-.004347,-.00697,
-.004684,-.006879,
-.005,-.006732,
-.005286,-.006532,
-.005532,-.006286,
-.005732,-.006,
-.005879,-.005684,
-.00597,-.005347,
-.006,-.005,
-.006,.005,
-.00597,.005347,
-.005879,.005684,
-.005732,.006,
-.005532,.006286,
-.005286,.006532,
-.005,.006732,
-.004684,.006879,
-.004347,.00697,
-.004,.007,
.004,.007,
.004347,.00697,
.004684,.006879,
.005,.006732,
.005286,.006532,
.005532,.006286,
.005732,.006,
.005879,.005684,
.00597,.005347,
.006,.005,
.006,-.005,
.00597,-.005347,
.005879,-.005684,
.005732,-.006,
.005532,-.006286,
.005286,-.006532,
.005,-.006732,
.004684,-.006879,
.004347,-.00697,
.004,-.007,
0.0*
%
%ADD52MACRO52*%
%AMMACRO39*
4,1,40,.007,.004,
.007,-.004,
.00697,-.004347,
.006879,-.004684,
.006732,-.005,
.006532,-.005286,
.006286,-.005532,
.006,-.005732,
.005684,-.005879,
.005347,-.00597,
.005,-.006,
-.005,-.006,
-.005347,-.00597,
-.005684,-.005879,
-.006,-.005732,
-.006286,-.005532,
-.006532,-.005286,
-.006732,-.005,
-.006879,-.004684,
-.00697,-.004347,
-.007,-.004,
-.007,.004,
-.00697,.004347,
-.006879,.004684,
-.006732,.005,
-.006532,.005286,
-.006286,.005532,
-.006,.005732,
-.005684,.005879,
-.005347,.00597,
-.005,.006,
.005,.006,
.005347,.00597,
.005684,.005879,
.006,.005732,
.006286,.005532,
.006532,.005286,
.006732,.005,
.006879,.004684,
.00697,.004347,
.007,.004,
0.0*
%
%ADD39MACRO39*%
%ADD74C,.107*%
%ADD33C,.126*%
%ADD40R,.045X.055*%
%ADD72O,.189X.126*%
%ADD64C,.128*%
%ADD44R,.016X.048*%
%ADD41R,.055X.045*%
%ADD45C,.138*%
%ADD10C,.158*%
%AMMACRO59*
4,1,40,-.007,.0225,
-.008389,.022378,
-.009736,.022018,
-.011,.021428,
-.012142,.020628,
-.013128,.019642,
-.013928,.0185,
-.014518,.017236,
-.014878,.015889,
-.015,.0145,
-.015,-.0145,
-.014878,-.015889,
-.014518,-.017236,
-.013928,-.0185,
-.013128,-.019642,
-.012142,-.020628,
-.011,-.021428,
-.009736,-.022018,
-.008389,-.022378,
-.007,-.0225,
.007,-.0225,
.008389,-.022378,
.009736,-.022018,
.011,-.021428,
.012142,-.020628,
.013128,-.019642,
.013928,-.0185,
.014518,-.017236,
.014878,-.015889,
.015,-.0145,
.015,.0145,
.014878,.015889,
.014518,.017236,
.013928,.0185,
.013128,.019642,
.012142,.020628,
.011,.021428,
.009736,.022018,
.008389,.022378,
.007,.0225,
-.007,.0225,
0.0*
%
%ADD59MACRO59*%
%AMMACRO54*
4,1,40,.024,-.012,
.024,.012,
.023878,.013389,
.023518,.014736,
.022928,.016,
.022128,.017142,
.021142,.018128,
.02,.018928,
.018736,.019518,
.017389,.019878,
.016,.02,
-.016,.02,
-.017389,.019878,
-.018736,.019518,
-.02,.018928,
-.021142,.018128,
-.022128,.017142,
-.022928,.016,
-.023518,.014736,
-.023878,.013389,
-.024,.012,
-.024,-.012,
-.023878,-.013389,
-.023518,-.014736,
-.022928,-.016,
-.022128,-.017142,
-.021142,-.018128,
-.02,-.018928,
-.018736,-.019518,
-.017389,-.019878,
-.016,-.02,
.016,-.02,
.017389,-.019878,
.018736,-.019518,
.02,-.018928,
.021142,-.018128,
.022128,-.017142,
.022928,-.016,
.023518,-.014736,
.023878,-.013389,
.024,-.012,
0.0*
%
%ADD54MACRO54*%
%AMMACRO47*
4,1,40,.008,-.012,
-.008,-.012,
-.008695,-.011939,
-.009368,-.011759,
-.01,-.011464,
-.010571,-.011064,
-.011064,-.010571,
-.011464,-.01,
-.011759,-.009368,
-.011939,-.008695,
-.012,-.008,
-.012,.008,
-.011939,.008695,
-.011759,.009368,
-.011464,.01,
-.011064,.010571,
-.010571,.011064,
-.01,.011464,
-.009368,.011759,
-.008695,.011939,
-.008,.012,
.008,.012,
.008695,.011939,
.009368,.011759,
.01,.011464,
.010571,.011064,
.011064,.010571,
.011464,.01,
.011759,.009368,
.011939,.008695,
.012,.008,
.012,-.008,
.011939,-.008695,
.011759,-.009368,
.011464,-.01,
.011064,-.010571,
.010571,-.011064,
.01,-.011464,
.009368,-.011759,
.008695,-.011939,
.008,-.012,
0.0*
%
%ADD47MACRO47*%
%AMMACRO24*
4,1,40,.012,.008,
.012,-.008,
.011939,-.008695,
.011759,-.009368,
.011464,-.01,
.011064,-.010571,
.010571,-.011064,
.01,-.011464,
.009368,-.011759,
.008695,-.011939,
.008,-.012,
-.008,-.012,
-.008695,-.011939,
-.009368,-.011759,
-.01,-.011464,
-.010571,-.011064,
-.011064,-.010571,
-.011464,-.01,
-.011759,-.009368,
-.011939,-.008695,
-.012,-.008,
-.012,.008,
-.011939,.008695,
-.011759,.009368,
-.011464,.01,
-.011064,.010571,
-.010571,.011064,
-.01,.011464,
-.009368,.011759,
-.008695,.011939,
-.008,.012,
.008,.012,
.008695,.011939,
.009368,.011759,
.01,.011464,
.010571,.011064,
.011064,.010571,
.011464,.01,
.011759,.009368,
.011939,.008695,
.012,.008,
0.0*
%
%ADD24MACRO24*%
%AMMACRO17*
4,1,40,-.007,.011,
.007,.011,
.007695,.010939,
.008368,.010759,
.009,.010464,
.009571,.010064,
.010064,.009571,
.010464,.009,
.010759,.008368,
.010939,.007695,
.011,.007,
.011,-.007,
.010939,-.007695,
.010759,-.008368,
.010464,-.009,
.010064,-.009571,
.009571,-.010064,
.009,-.010464,
.008368,-.010759,
.007695,-.010939,
.007,-.011,
-.007,-.011,
-.007695,-.010939,
-.008368,-.010759,
-.009,-.010464,
-.009571,-.010064,
-.010064,-.009571,
-.010464,-.009,
-.010759,-.008368,
-.010939,-.007695,
-.011,-.007,
-.011,.007,
-.010939,.007695,
-.010759,.008368,
-.010464,.009,
-.010064,.009571,
-.009571,.010064,
-.009,.010464,
-.008368,.010759,
-.007695,.010939,
-.007,.011,
0.0*
%
%ADD17MACRO17*%
%AMMACRO19*
4,1,40,.011,.007,
.011,-.007,
.010939,-.007695,
.010759,-.008368,
.010464,-.009,
.010064,-.009571,
.009571,-.010064,
.009,-.010464,
.008368,-.010759,
.007695,-.010939,
.007,-.011,
-.007,-.011,
-.007695,-.010939,
-.008368,-.010759,
-.009,-.010464,
-.009571,-.010064,
-.010064,-.009571,
-.010464,-.009,
-.010759,-.008368,
-.010939,-.007695,
-.011,-.007,
-.011,.007,
-.010939,.007695,
-.010759,.008368,
-.010464,.009,
-.010064,.009571,
-.009571,.010064,
-.009,.010464,
-.008368,.010759,
-.007695,.010939,
-.007,.011,
.007,.011,
.007695,.010939,
.008368,.010759,
.009,.010464,
.009571,.010064,
.010064,.009571,
.010464,.009,
.010759,.008368,
.010939,.007695,
.011,.007,
0.0*
%
%ADD19MACRO19*%
%AMMACRO69*
4,1,40,.013,-.017,
-.013,-.017,
-.013695,-.016939,
-.014368,-.016759,
-.015,-.016464,
-.015571,-.016064,
-.016064,-.015571,
-.016464,-.015,
-.016759,-.014368,
-.016939,-.013695,
-.017,-.013,
-.017,.013,
-.016939,.013695,
-.016759,.014368,
-.016464,.015,
-.016064,.015571,
-.015571,.016064,
-.015,.016464,
-.014368,.016759,
-.013695,.016939,
-.013,.017,
.013,.017,
.013695,.016939,
.014368,.016759,
.015,.016464,
.015571,.016064,
.016064,.015571,
.016464,.015,
.016759,.014368,
.016939,.013695,
.017,.013,
.017,-.013,
.016939,-.013695,
.016759,-.014368,
.016464,-.015,
.016064,-.015571,
.015571,-.016064,
.015,-.016464,
.014368,-.016759,
.013695,-.016939,
.013,-.017,
0.0*
%
%ADD69MACRO69*%
%AMMACRO37*
4,1,40,-.017,-.013,
-.017,.013,
-.016939,.013695,
-.016759,.014368,
-.016464,.015,
-.016064,.015571,
-.015571,.016064,
-.015,.016464,
-.014368,.016759,
-.013695,.016939,
-.013,.017,
.013,.017,
.013695,.016939,
.014368,.016759,
.015,.016464,
.015571,.016064,
.016064,.015571,
.016464,.015,
.016759,.014368,
.016939,.013695,
.017,.013,
.017,-.013,
.016939,-.013695,
.016759,-.014368,
.016464,-.015,
.016064,-.015571,
.015571,-.016064,
.015,-.016464,
.014368,-.016759,
.013695,-.016939,
.013,-.017,
-.013,-.017,
-.013695,-.016939,
-.014368,-.016759,
-.015,-.016464,
-.015571,-.016064,
-.016064,-.015571,
-.016464,-.015,
-.016759,-.014368,
-.016939,-.013695,
-.017,-.013,
0.0*
%
%ADD37MACRO37*%
%AMMACRO81*
4,1,6,.005,-.0135,
.005,-.0065,
.025,.0135,
-.025,.0135,
-.005,-.0065,
-.005,-.0135,
.005,-.0135,
0.0*
%
%ADD81MACRO81*%
%AMMACRO46*
4,1,40,.008,-.012,
-.008,-.012,
-.008695,-.011939,
-.009368,-.011759,
-.01,-.011464,
-.010571,-.011064,
-.011064,-.010571,
-.011464,-.01,
-.011759,-.009368,
-.011939,-.008695,
-.012,-.008,
-.012,.008,
-.011939,.008695,
-.011759,.009368,
-.011464,.01,
-.011064,.010571,
-.010571,.011064,
-.01,.011464,
-.009368,.011759,
-.008695,.011939,
-.008,.012,
.008,.012,
.008695,.011939,
.009368,.011759,
.01,.011464,
.010571,.011064,
.011064,.010571,
.011464,.01,
.011759,.009368,
.011939,.008695,
.012,.008,
.012,-.008,
.011939,-.008695,
.011759,-.009368,
.011464,-.01,
.011064,-.010571,
.010571,-.011064,
.01,-.011464,
.009368,-.011759,
.008695,-.011939,
.008,-.012,
0.0*
%
%ADD46MACRO46*%
%AMMACRO25*
4,1,40,.012,.008,
.012,-.008,
.011939,-.008695,
.011759,-.009368,
.011464,-.01,
.011064,-.010571,
.010571,-.011064,
.01,-.011464,
.009368,-.011759,
.008695,-.011939,
.008,-.012,
-.008,-.012,
-.008695,-.011939,
-.009368,-.011759,
-.01,-.011464,
-.010571,-.011064,
-.011064,-.010571,
-.011464,-.01,
-.011759,-.009368,
-.011939,-.008695,
-.012,-.008,
-.012,.008,
-.011939,.008695,
-.011759,.009368,
-.011464,.01,
-.011064,.010571,
-.010571,.011064,
-.01,.011464,
-.009368,.011759,
-.008695,.011939,
-.008,.012,
.008,.012,
.008695,.011939,
.009368,.011759,
.01,.011464,
.010571,.011064,
.011064,.010571,
.011464,.01,
.011759,.009368,
.011939,.008695,
.012,.008,
0.0*
%
%ADD25MACRO25*%
%AMMACRO18*
4,1,40,-.007,.011,
.007,.011,
.007695,.010939,
.008368,.010759,
.009,.010464,
.009571,.010064,
.010064,.009571,
.010464,.009,
.010759,.008368,
.010939,.007695,
.011,.007,
.011,-.007,
.010939,-.007695,
.010759,-.008368,
.010464,-.009,
.010064,-.009571,
.009571,-.010064,
.009,-.010464,
.008368,-.010759,
.007695,-.010939,
.007,-.011,
-.007,-.011,
-.007695,-.010939,
-.008368,-.010759,
-.009,-.010464,
-.009571,-.010064,
-.010064,-.009571,
-.010464,-.009,
-.010759,-.008368,
-.010939,-.007695,
-.011,-.007,
-.011,.007,
-.010939,.007695,
-.010759,.008368,
-.010464,.009,
-.010064,.009571,
-.009571,.010064,
-.009,.010464,
-.008368,.010759,
-.007695,.010939,
-.007,.011,
0.0*
%
%ADD18MACRO18*%
%ADD83C,.02*%
%ADD84C,.006*%
G75*
%LPD*%
G75*
G36*
G01X187599Y1023622D02*
X107677D01*
Y1001610D01*
X187599D01*
Y1023622D01*
G37*
G36*
G01X597048D02*
X265158D01*
Y1001610D01*
X597048D01*
Y1023622D01*
G37*
G36*
G01X797048D02*
X717126D01*
Y1001610D01*
X797048D01*
Y1023622D01*
G37*
G36*
G01X1330000Y32000D02*
Y18000D01*
X1318000D01*
Y32000D01*
Y34000D01*
X1330000D01*
Y32000D01*
G37*
G54D10*
X19272Y337795D03*
Y396850D03*
X98838Y337795D03*
Y396850D03*
G54D11*
X21220Y373228D03*
X96890D03*
X157480Y283071D03*
X220472D03*
G54D20*
X43520Y914388D03*
X48020D03*
X52520D03*
X57020D03*
X61520D03*
X66020D03*
X99804Y916420D03*
X103804D03*
X107804D03*
X111804D03*
X115804D03*
X119804D03*
X123804D03*
X127804D03*
X131804D03*
X135804D03*
X313000Y92700D03*
X330000Y87700D03*
X314453Y248552D03*
X344040Y210700D03*
X357040D03*
X348540D03*
X353040D03*
X351000Y396200D03*
X373200Y183240D03*
X371429Y207200D03*
X380829Y191300D03*
X393000Y944200D03*
X406555Y326700D03*
X405000Y944200D03*
X409000D03*
X397000D03*
X401000D03*
X425278Y812200D03*
X413000Y944200D03*
X417000D03*
X429940Y155000D03*
X444055Y298700D03*
X431778Y812200D03*
X431278Y875700D03*
X437778D03*
X456278Y812200D03*
X460778Y875700D03*
X462778Y812200D03*
X467278Y875700D03*
X544178Y968200D03*
X548555Y345200D03*
X554955Y371600D03*
X558955D03*
X641000Y475700D03*
X646500Y452200D03*
X678500Y410200D03*
X787000Y414700D03*
X1010500Y78200D03*
X1178500Y647700D03*
X1281000Y690700D03*
Y709200D03*
X1273000Y701700D03*
X1281000D03*
X1277000Y719700D03*
X1281000Y727700D03*
X1292500Y416700D03*
X1350084Y284368D03*
X1372300Y284400D03*
X1384300D03*
G54D12*
X15000Y1008622D03*
X90119Y72219D03*
X227041Y1008622D03*
X653974Y1008621D03*
X955315Y850829D03*
X1157095Y128841D03*
X1385000Y1008622D03*
X1387875Y-15015D03*
G54D30*
X200000Y391500D03*
Y401500D03*
Y411500D03*
Y421500D03*
X216500Y391500D03*
Y401500D03*
Y411500D03*
Y421500D03*
X1296000Y319500D03*
Y329500D03*
X1367067Y42323D03*
Y60039D03*
Y78544D03*
Y96260D03*
X1392657Y42323D03*
Y60039D03*
Y78544D03*
Y96260D03*
G54D21*
X56000Y7500D03*
X57500Y993500D03*
X422678Y895000D03*
X483178Y821000D03*
X1322500Y69000D03*
X1367500Y995000D03*
G54D40*
X314753Y235852D03*
X307153D03*
X314753Y227852D03*
X307153D03*
X389629Y181700D03*
X382029D03*
X389600Y206929D03*
X382000D03*
X394355Y441000D03*
X386755D03*
X458355Y314600D03*
X471887Y302717D03*
X464287D03*
X465955Y314600D03*
X472455D03*
X480055D03*
X486478Y875500D03*
X494078D03*
X486478Y867500D03*
X494078D03*
X506629Y141000D03*
X499055Y337700D03*
X506655D03*
X499755Y385500D03*
X507355D03*
X499755Y400500D03*
X507355D03*
X514229Y141000D03*
X656162Y465964D03*
X663762D03*
X688300Y446000D03*
X680700D03*
X718948Y107500D03*
X726548D03*
X1050200Y140500D03*
X1057800D03*
X1275300Y433000D03*
X1267700D03*
G54D22*
X59504Y669720D03*
X60536Y693503D03*
Y690003D03*
X64972Y822004D03*
X77472Y730004D03*
X74472Y752504D03*
X70004Y853220D03*
X94504Y669720D03*
X95036Y694003D03*
Y690503D03*
X337129Y201500D03*
X348255Y538500D03*
Y542500D03*
X369689Y215420D03*
X377389Y215390D03*
X385069Y215400D03*
X405229Y165000D03*
X405129Y170500D03*
X412629D03*
X412729Y165000D03*
X405129Y183500D03*
Y177000D03*
X412629D03*
Y183500D03*
X405129Y190000D03*
X412629D03*
X427240Y139000D03*
X419740D03*
X420229Y165000D03*
X420129Y170500D03*
Y177000D03*
Y183500D03*
Y190000D03*
X434740Y139000D03*
X444255Y372500D03*
X455629Y118000D03*
X456755Y372500D03*
X464255D03*
X483629Y158500D03*
Y172500D03*
Y166000D03*
Y179000D03*
X487978Y832000D03*
X498655Y351500D03*
Y347500D03*
X522129Y141000D03*
X706916Y122784D03*
Y133284D03*
Y126284D03*
Y129784D03*
X1140668Y688284D03*
X1141800Y684800D03*
X1160800Y679300D03*
X1255700Y719500D03*
G54D13*
X35435Y373228D03*
X82675D03*
X180118Y729409D03*
Y739409D03*
X200118Y729409D03*
X190118D03*
X200118Y739409D03*
X190118D03*
X210118Y729409D03*
Y739409D03*
X230118Y729409D03*
X220118D03*
X230118Y739409D03*
X220118D03*
X250118Y729409D03*
X240118D03*
X250118Y739409D03*
X240118D03*
X260118Y729409D03*
Y739409D03*
X270118Y729409D03*
Y739409D03*
G54D31*
X185039Y1007910D03*
X594488D03*
X794488D03*
G36*
G01X254328Y92115D02*
G03Y92135I15750J10D01*
G01X262578D01*
G02Y92115I7500J-10D01*
G01X254328D01*
G37*
G36*
G01Y155107D02*
G03Y155127I15750J10D01*
G01X262578D01*
G02Y155107I7500J-10D01*
G01X254328D01*
G37*
G36*
G01X475194Y79911D02*
G03Y79931I15750J10D01*
G01X483444D01*
G02Y79911I7500J-10D01*
G01X475194D01*
G37*
G36*
G01Y255108D02*
G03Y255128I15750J10D01*
G01X483444D01*
G02Y255108I7500J-10D01*
G01X475194D01*
G37*
G36*
G01X728146Y353533D02*
G03Y353553I15750J10D01*
G01X736396D01*
G02Y353533I7500J-10D01*
G01X728146D01*
G37*
G36*
G01Y410619D02*
G03Y410639I15750J10D01*
G01X736396D01*
G02Y410619I7500J-10D01*
G01X728146D01*
G37*
G36*
G01X1289366Y87538D02*
G03Y87558I15750J10D01*
G01X1297616D01*
G02Y87538I7500J-10D01*
G01X1289366D01*
G37*
G36*
G01X1289367Y262735D02*
G03Y262755I15750J10D01*
G01X1297617D01*
G02Y262735I7500J-10D01*
G01X1289367D01*
G37*
G36*
G01X1361218Y147233D02*
G03Y147253I15750J10D01*
G01X1369468D01*
G02Y147233I7500J-10D01*
G01X1361218D01*
G37*
G36*
G01Y216525D02*
G03Y216545I15750J10D01*
G01X1369468D01*
G02Y216525I7500J-10D01*
G01X1361218D01*
G37*
G54D41*
X307953Y250652D03*
Y243052D03*
X326000Y67700D03*
Y75300D03*
X368500Y17300D03*
Y9700D03*
X391929Y156200D03*
Y163800D03*
X396500Y329300D03*
Y321700D03*
X401429Y197200D03*
Y204800D03*
X418929Y197200D03*
Y204800D03*
X480023Y420983D03*
Y428583D03*
X490429Y135300D03*
Y127700D03*
X498429Y135300D03*
Y127700D03*
X647000Y347700D03*
Y355300D03*
X739748Y137300D03*
Y129700D03*
X1211000Y705200D03*
Y712800D03*
X1227177Y198200D03*
Y205800D03*
G54D50*
X376000Y16300D03*
X381000D03*
X625500Y353800D03*
X640500D03*
X635500D03*
X630500D03*
X787000Y406300D03*
X1151000Y707800D03*
G54D23*
X63104Y669720D03*
X64136Y693503D03*
Y690003D03*
X81072Y730004D03*
X78072Y752504D03*
X68572Y822004D03*
X73604Y853220D03*
X98104Y669720D03*
X98636Y694003D03*
Y690503D03*
X340729Y201500D03*
X351855Y538500D03*
Y542500D03*
X373289Y215420D03*
X388669Y215400D03*
X380989Y215390D03*
X408829Y165000D03*
X408729Y170500D03*
Y183500D03*
Y177000D03*
Y190000D03*
X423340Y139000D03*
X423829Y165000D03*
X423729Y170500D03*
X416229D03*
X416329Y165000D03*
X423729Y177000D03*
X416229D03*
Y183500D03*
X423729D03*
Y190000D03*
X416229D03*
X438340Y139000D03*
X430840D03*
X459229Y118000D03*
X447855Y372500D03*
X460355D03*
X467855D03*
X487229Y158500D03*
Y172500D03*
Y166000D03*
Y179000D03*
X491578Y832000D03*
X502255Y351500D03*
Y347500D03*
X525729Y141000D03*
X710516Y122784D03*
Y133284D03*
Y126284D03*
Y129784D03*
X1144268Y688284D03*
X1145400Y684800D03*
X1164400Y679300D03*
X1259300Y719500D03*
G54D14*
X27004Y783420D03*
X23820Y795182D03*
X30312Y805489D03*
X49369Y767582D03*
X46304Y779520D03*
X40204Y788820D03*
X35747Y796605D03*
X43456Y803320D03*
X36904Y813020D03*
X38804Y843320D03*
X38500Y891500D03*
X46500Y879500D03*
X47880Y918798D03*
X68147Y734920D03*
X63167Y775783D03*
X52720Y832220D03*
X63879Y839879D03*
X56500Y874000D03*
X57770Y926520D03*
X55270Y920220D03*
X52770Y927420D03*
X62770Y926400D03*
X60270Y918820D03*
X71846Y726562D03*
X77699Y738515D03*
X77504Y767420D03*
X84221Y831279D03*
X94804Y718720D03*
X99804Y727120D03*
X86704Y740720D03*
X87104Y871920D03*
X94904Y869720D03*
X99804Y920520D03*
X93604Y938795D03*
X109054Y898620D03*
X103312Y904712D03*
X116554Y909020D03*
X114054Y900220D03*
X107804Y908820D03*
X117202Y926322D03*
X112476Y924744D03*
X107804Y920720D03*
X106803Y927321D03*
X132123Y318877D03*
X123654Y320953D03*
X124054Y897920D03*
X122904Y907820D03*
X119054Y901520D03*
X119804Y920320D03*
X131404Y925520D03*
X127804Y920520D03*
X123804Y925720D03*
X135804Y920020D03*
X182500Y547500D03*
X229000Y493500D03*
X231200Y509800D03*
X227755Y520900D03*
X242000Y509600D03*
X241200Y501800D03*
X237055Y516500D03*
X249000Y513700D03*
X234155Y530700D03*
X248045Y528970D03*
X241600Y522500D03*
X248700Y548800D03*
X259055Y497200D03*
X264665Y487730D03*
X250200Y501400D03*
X258592Y511993D03*
X255829Y527924D03*
X263400Y527900D03*
X253679Y520037D03*
X264615Y519970D03*
X259000Y537700D03*
X262200Y545000D03*
X263700Y552500D03*
X255500Y552600D03*
X271655Y528210D03*
X280800Y532800D03*
X275055Y517960D03*
X281500Y523500D03*
X271986Y523421D03*
X278000Y543700D03*
X274200Y537200D03*
X271400Y547800D03*
X266635Y537120D03*
X277500Y977000D03*
X291000Y98500D03*
X293495Y494300D03*
X294692Y503484D03*
X292605Y536560D03*
X309500Y75000D03*
X310000Y102500D03*
X301600Y110600D03*
X302329Y223800D03*
X306700Y265500D03*
X314588Y361696D03*
X303354Y358650D03*
X308474Y373060D03*
X316000Y50000D03*
X328000Y93000D03*
X323000D03*
X316598Y91500D03*
X320500Y124000D03*
X316400Y222500D03*
X317529Y241600D03*
X330500Y287000D03*
X322500Y298000D03*
X325100Y364000D03*
X337500Y68500D03*
X337000Y73500D03*
X342900Y120040D03*
X346129Y188200D03*
X345540Y202000D03*
X347040Y193000D03*
X336200Y366275D03*
X344000Y368315D03*
X336855Y458900D03*
X349000Y78000D03*
X358080Y184300D03*
X354410Y176460D03*
X350040Y184500D03*
X361929Y174000D03*
X350040Y198500D03*
X353040Y202500D03*
X357540Y199500D03*
X358440Y189300D03*
X348800Y221000D03*
X363662Y373838D03*
X359855Y440400D03*
X359455Y448300D03*
X352917Y443700D03*
X356500Y622500D03*
X361000Y925490D03*
X363000Y936000D03*
X361646Y990784D03*
X376140Y186800D03*
X366729Y174000D03*
X377929D03*
X375040Y197500D03*
X373500Y235200D03*
X376600Y350310D03*
X379500Y377000D03*
X374600Y413540D03*
X374900Y404300D03*
X367000Y412000D03*
X364430Y424300D03*
X367800Y420300D03*
X375100Y436955D03*
X369900Y446932D03*
X367500Y436355D03*
X366255Y456700D03*
X365940Y464200D03*
X369555Y470800D03*
X375600Y909600D03*
X371900Y901400D03*
X370500Y941500D03*
X377000Y942000D03*
X366678Y990500D03*
X380500Y34500D03*
X382130Y229780D03*
X396329Y227800D03*
X390500Y250000D03*
Y257500D03*
X385425Y348740D03*
X386500Y362100D03*
X387519Y379375D03*
X392900Y388000D03*
X383000Y401000D03*
X387669Y387355D03*
X386455Y392000D03*
X380555Y407000D03*
X394555Y426000D03*
X383250Y910750D03*
X392575Y924575D03*
X381000Y919500D03*
X393000Y949000D03*
X387500Y944500D03*
X412929Y145500D03*
X408429Y219700D03*
X401929Y225300D03*
X405000Y272000D03*
X410330Y326500D03*
X405555Y379000D03*
X401055Y381500D03*
X404555Y412000D03*
X399555Y426000D03*
X406055Y423700D03*
X400200Y893925D03*
X400000Y888500D03*
X399500Y908500D03*
X402500Y927500D03*
X398000Y949500D03*
X411574Y971926D03*
X409000Y992000D03*
X403900Y990500D03*
X421540Y123500D03*
Y118500D03*
X428040Y123500D03*
X426786Y113500D03*
X418040Y132500D03*
X425229Y128700D03*
X422940Y133000D03*
X428040D03*
X423329Y145620D03*
X417729Y145500D03*
X420219Y151810D03*
X426429Y196000D03*
X425126Y221124D03*
X425532Y228137D03*
X416500Y229500D03*
X417500Y253000D03*
X429500Y307500D03*
X422952Y325500D03*
X421055Y321000D03*
X413555Y322000D03*
X424000Y377000D03*
X415755Y408200D03*
X418500Y850500D03*
X417000Y969000D03*
X418071Y974956D03*
X414000Y977500D03*
X433040Y119000D03*
X438540D03*
X444540Y122500D03*
X443042Y139065D03*
X433040Y132500D03*
X430040Y128500D03*
X438540Y132500D03*
X435040Y128000D03*
X445059Y127830D03*
X443429Y132400D03*
X429939Y146020D03*
X442429Y171500D03*
X442099Y187600D03*
X440009Y225589D03*
X431321Y232880D03*
X435659Y223364D03*
X445000Y223000D03*
X438000Y245000D03*
X432600Y291400D03*
X442555Y324000D03*
X432555Y333500D03*
X434155Y327000D03*
X436055Y342000D03*
X436555Y337000D03*
X432000Y366000D03*
X431298Y832710D03*
X430878Y842800D03*
X436978Y831000D03*
X430978Y837500D03*
X431126Y848348D03*
X431466Y858563D03*
X430936Y853145D03*
X437978Y859000D03*
X432723Y970223D03*
X459429Y102700D03*
X452829Y99000D03*
X448229Y133000D03*
X452159Y125370D03*
X452929Y134500D03*
X458349Y137762D03*
X459929Y128500D03*
X454929Y130000D03*
X447349Y149920D03*
X450989Y153950D03*
X458839Y147900D03*
X450255Y140258D03*
X449429Y145500D03*
X454479Y150150D03*
X456929Y143000D03*
X455229Y162460D03*
X456309Y157740D03*
X451669Y159120D03*
X447129Y157000D03*
X447489Y162190D03*
X458129Y167900D03*
X461272Y159293D03*
X455429Y185500D03*
X448876Y195275D03*
X450237Y200375D03*
X460500Y196000D03*
X461000Y216500D03*
X449500Y220925D03*
X452509Y226958D03*
X448055Y311500D03*
X452555Y316500D03*
X447055Y321500D03*
X456055D03*
X452555Y352900D03*
X448555Y338000D03*
X456278Y829500D03*
X465329Y111900D03*
X463429Y139000D03*
X465429Y127000D03*
X468600Y136700D03*
X462539Y144270D03*
X462500Y154000D03*
Y164000D03*
X475900Y173800D03*
X472000Y184500D03*
X467010Y186000D03*
X465807Y197940D03*
X462500Y221500D03*
X464000Y243500D03*
X476700Y303800D03*
X468555Y323000D03*
X463055Y322500D03*
X472055Y334000D03*
X475957Y322537D03*
X467255Y342600D03*
X472055Y341500D03*
X462555Y346000D03*
X476978Y830500D03*
X479000Y116500D03*
X480429Y144100D03*
X494829Y140500D03*
X493800Y172000D03*
X485500Y313000D03*
X493455Y345000D03*
X485500Y400500D03*
X479578Y843200D03*
X479078Y836000D03*
X483878Y839300D03*
X479278Y850000D03*
X484178Y846984D03*
X480578Y856000D03*
X499929Y146000D03*
X509200Y146700D03*
X510500Y237300D03*
X506000Y239500D03*
X511500Y345000D03*
X497500Y833000D03*
X500500Y863500D03*
X523129Y132600D03*
X526500Y145000D03*
X524000Y243500D03*
X531500Y124500D03*
X543500Y179000D03*
X538500Y188500D03*
X542500Y215500D03*
X540500Y211000D03*
X544500Y224500D03*
X544178Y956000D03*
Y973500D03*
X556500Y184500D03*
X550500D03*
X560468Y203788D03*
X555500Y190500D03*
X555000Y219500D03*
X550075Y212500D03*
X552435Y232150D03*
X556455Y337700D03*
X550755Y337500D03*
X568500Y180500D03*
X566900Y195900D03*
X562441Y199072D03*
X564500Y217000D03*
X564000Y212000D03*
X568000Y239000D03*
X584500Y240500D03*
X613500Y451500D03*
X626000Y676000D03*
X632500Y440100D03*
X650300Y336400D03*
X654600Y447700D03*
X654000Y455900D03*
X649100Y471700D03*
X666500Y359500D03*
X670919Y406750D03*
X659700Y432600D03*
X664900Y441800D03*
X675411Y446000D03*
X668800Y465993D03*
X663360Y483321D03*
X674000Y888900D03*
X669000Y887385D03*
X671500Y899000D03*
X679900Y470200D03*
X701748Y125400D03*
X693100Y445800D03*
X705600Y769300D03*
X701400Y883900D03*
X739000Y120400D03*
X733784Y861131D03*
X742800Y173600D03*
X747775Y710275D03*
X748500Y858700D03*
X765000Y351500D03*
X768000Y760600D03*
X762900Y767800D03*
X763593Y858444D03*
X760500Y866283D03*
X769800Y977300D03*
X782600Y414750D03*
X778688Y470790D03*
X791000Y466603D03*
X811600Y477100D03*
X821000Y883700D03*
X825500Y669000D03*
X854200Y764700D03*
X882500Y339500D03*
X883200Y451500D03*
X892000Y610500D03*
X945720Y478280D03*
X961000Y495000D03*
X980400Y435300D03*
X994000Y643600D03*
X1015500Y871500D03*
X1025500Y140500D03*
X1036000Y178000D03*
X1029500Y653000D03*
X1045000Y141500D03*
X1051034Y173534D03*
X1050500Y680500D03*
X1054000Y124500D03*
X1063000Y140500D03*
X1068000Y645329D03*
X1066300Y658800D03*
X1055000Y664500D03*
X1058000Y677500D03*
X1065000Y677000D03*
X1056000Y801500D03*
X1078500Y140500D03*
X1070000Y145500D03*
X1085896Y551500D03*
X1071977Y630000D03*
X1085000Y667500D03*
X1088000Y609500D03*
X1098000Y659000D03*
X1088000Y677000D03*
X1102500Y666800D03*
X1093000Y670000D03*
X1095500Y681706D03*
X1087400Y686000D03*
X1094250Y690050D03*
X1087100Y695000D03*
X1094000Y699500D03*
X1086500Y713000D03*
X1092812Y708500D03*
X1086600Y704000D03*
X1086300Y720100D03*
X1093600Y716100D03*
X1087000Y739200D03*
X1093975Y742500D03*
X1099500Y866000D03*
X1110500Y660076D03*
X1118200Y657400D03*
X1115000Y650000D03*
X1107524Y676124D03*
X1110700Y669200D03*
X1112400Y678500D03*
X1112600Y713100D03*
X1106400Y714400D03*
X1116500Y718300D03*
X1115800Y766400D03*
X1110400Y769500D03*
X1117630Y779565D03*
X1117600Y787000D03*
X1133200Y633500D03*
X1127610Y663660D03*
X1133000Y657000D03*
X1127800Y656204D03*
X1121760Y665640D03*
X1119400Y706210D03*
X1127554Y724482D03*
X1128000Y718000D03*
X1132902Y746400D03*
X1134000Y757350D03*
X1119295Y774903D03*
X1123852Y776918D03*
X1123233Y772157D03*
X1128378Y774146D03*
X1123500Y796000D03*
X1146500Y539000D03*
X1136200Y574100D03*
X1145800Y576200D03*
X1143500Y655500D03*
Y660500D03*
X1151000Y656500D03*
X1137386Y660414D03*
X1138760Y671560D03*
X1141790Y667130D03*
X1139000Y678600D03*
X1145400Y673100D03*
X1135724Y692464D03*
X1142900Y705300D03*
X1140586Y725300D03*
X1137286Y731000D03*
X1142811Y731100D03*
X1144075Y739375D03*
X1138900Y761600D03*
X1143862Y770957D03*
X1135900Y792500D03*
X1148061Y793765D03*
X1148760Y789016D03*
X1151800Y796800D03*
X1145800Y816000D03*
X1159000Y396500D03*
X1157700Y528200D03*
X1154100Y539600D03*
X1156179Y615121D03*
X1159500Y624000D03*
X1152600Y634600D03*
X1164000Y655000D03*
Y660000D03*
X1159000Y652176D03*
X1156500Y657500D03*
X1154000Y652500D03*
X1167280Y672050D03*
X1158780Y670430D03*
X1168000Y706000D03*
X1163700Y714400D03*
X1154610Y711340D03*
X1152709Y720064D03*
X1156080Y723482D03*
X1160000Y734480D03*
X1164100Y740000D03*
X1157500Y739200D03*
X1151900Y740500D03*
X1156700Y744100D03*
X1161324Y749550D03*
X1161128Y759674D03*
X1164178Y755967D03*
X1163600Y777900D03*
X1158801Y778038D03*
X1166500Y773900D03*
X1158600Y790900D03*
X1157841Y784725D03*
X1165063Y790400D03*
X1181400Y592100D03*
X1181884Y614211D03*
X1182500Y623500D03*
X1171775Y630000D03*
X1169075Y617500D03*
X1175500Y660000D03*
X1183000Y656000D03*
X1182500Y664500D03*
X1171080Y675530D03*
X1173500Y683000D03*
X1170000Y710790D03*
X1173600Y704500D03*
X1184500Y730500D03*
X1180210Y718150D03*
X1174500Y753000D03*
X1168465Y779808D03*
X1173263Y779656D03*
X1170500Y768000D03*
X1174100Y774900D03*
X1173902Y784414D03*
X1170300Y787985D03*
X1185500Y362500D03*
X1196500Y640000D03*
X1191000Y651500D03*
X1187230Y702250D03*
X1193960Y713250D03*
X1194000Y703000D03*
X1190760Y719450D03*
X1196100Y719100D03*
X1184850Y720120D03*
X1187330Y715720D03*
X1194573Y727580D03*
X1193100Y736900D03*
X1213677Y191000D03*
X1207500Y239500D03*
X1209500Y546000D03*
X1207700Y601800D03*
X1213000Y624500D03*
X1216000Y664500D03*
X1217500Y705200D03*
X1209000Y722500D03*
X1206000Y731000D03*
X1216500Y735000D03*
X1202200Y741600D03*
X1231000Y543775D03*
X1219300Y567800D03*
X1222500Y620500D03*
X1225500Y653000D03*
X1226500Y668500D03*
X1222000Y666500D03*
X1218040Y716000D03*
X1229500Y735700D03*
X1241500Y654000D03*
X1236000Y660500D03*
X1240500Y679500D03*
X1246700Y675500D03*
X1243000Y691500D03*
X1235000Y687500D03*
X1245500Y683500D03*
X1234500Y695500D03*
X1243500Y699500D03*
X1235000Y703500D03*
X1243000Y707500D03*
X1235500Y711500D03*
X1241000Y730400D03*
X1243000Y715500D03*
X1234700Y733700D03*
X1256500Y431000D03*
X1251500Y536000D03*
X1264000Y613500D03*
X1257500Y620500D03*
X1269000Y252000D03*
X1280500Y433000D03*
X1268500Y427000D03*
X1272000Y463500D03*
X1267500Y625500D03*
X1275500Y647000D03*
X1278000Y657000D03*
X1270000Y794000D03*
X1274000Y875000D03*
X1288000Y470000D03*
X1293500Y607500D03*
X1288000Y674687D03*
X1293000Y682500D03*
X1297750Y691350D03*
X1294000Y712000D03*
X1294500Y720000D03*
X1296000Y733000D03*
X1286500Y747500D03*
X1312750Y314000D03*
X1300000Y669000D03*
X1315000Y704000D03*
X1301800Y727199D03*
X1300500Y739750D03*
X1322500Y299000D03*
X1324000Y290500D03*
X1330500Y452500D03*
X1324145Y668376D03*
X1320500Y671500D03*
X1331500Y703000D03*
X1342000Y107000D03*
X1342500Y452500D03*
X1350000Y105500D03*
X1349800Y257900D03*
X1354000Y281000D03*
X1349000Y399500D03*
X1358250Y445750D03*
X1351000Y452000D03*
X1377000Y277000D03*
X1381500Y288500D03*
X1376300Y289000D03*
X1365800Y306600D03*
X1375000Y409000D03*
X1372000Y495500D03*
X1384500Y271000D03*
Y327500D03*
G54D24*
X83788Y853252D03*
X119504Y796720D03*
Y800720D03*
X387129Y170500D03*
Y174000D03*
X386700Y197200D03*
Y200600D03*
X387200Y190000D03*
X395759Y215180D03*
X412240Y139000D03*
X397629Y170500D03*
X397729Y165000D03*
X397629Y177000D03*
Y183500D03*
Y190000D03*
X412329Y214680D03*
X406255Y338850D03*
X407155Y372000D03*
X424929Y205200D03*
X424869Y208670D03*
X419939Y214650D03*
X421755Y372500D03*
X423478Y824500D03*
X423378Y864000D03*
X435029Y151710D03*
X434079Y158620D03*
X434129Y170860D03*
X434219Y164850D03*
X434129Y177400D03*
X434329Y183800D03*
X434449Y202480D03*
X434129Y189750D03*
X434629Y196000D03*
X434439Y208870D03*
X456255Y326500D03*
X1006700Y70500D03*
X1060200Y120500D03*
X1166700Y685500D03*
X1166668Y695284D03*
Y689284D03*
Y700284D03*
X1159700Y704500D03*
X1176200Y701300D03*
X1354700Y456000D03*
G54D33*
X270078Y92125D03*
Y155117D03*
X490944Y79921D03*
Y255118D03*
X743897Y353543D03*
Y410629D03*
X1305117Y87548D03*
Y262745D03*
X1376968Y147243D03*
Y216535D03*
G54D15*
X47476Y397079D03*
X43976D03*
X62976D03*
X56976D03*
X66476D03*
X53476D03*
X75476D03*
X71976D03*
X165795Y307509D03*
X179295D03*
X175295D03*
X169795D03*
X213795Y304009D03*
X209795D03*
X203795D03*
X200295D03*
X269678Y965800D03*
X273678D03*
X334000Y84300D03*
X346000Y116340D03*
X349000Y15300D03*
X361500D03*
X358000D03*
X360819Y210840D03*
X371239Y191970D03*
X371299Y199540D03*
X376929Y208800D03*
X386300Y164800D03*
X409429Y160800D03*
X399429D03*
X402929D03*
X422200Y160600D03*
X418714Y160650D03*
X415314D03*
X450678Y812300D03*
X507055Y412300D03*
X733716Y135584D03*
X730216D03*
X1006500Y78300D03*
X1277000Y701800D03*
X1273000Y719800D03*
G54D42*
X312000Y292700D03*
X321500Y85200D03*
X326000D03*
X317000D03*
X329500Y294200D03*
X341000Y116240D03*
X353500Y15200D03*
X393929Y224700D03*
X394555Y434700D03*
X402929Y233700D03*
X406929D03*
X399555Y434700D03*
X425940Y155000D03*
X413429Y240200D03*
X426523Y326983D03*
X425278Y808700D03*
X435055Y287700D03*
X430523Y326983D03*
X431778Y808700D03*
X437778Y879200D03*
X431278D03*
X456278Y808700D03*
X460778Y879200D03*
X462778Y808700D03*
X467278Y879200D03*
X509555Y420200D03*
X552555Y345200D03*
X556555D03*
X651000Y452200D03*
X645500Y475700D03*
X1137500Y656200D03*
X1166000Y648200D03*
X1153000D03*
X1158000D03*
X1162000D03*
X1213000Y634200D03*
X1209000D03*
X1217000D03*
X1260500Y641200D03*
X1277000Y690700D03*
X1273000Y709200D03*
X1281000Y719700D03*
X1277000Y727700D03*
X1358584Y284368D03*
X1376300Y284400D03*
X1380300D03*
X1384500Y322700D03*
G54D60*
X537994Y303150D03*
X825984D03*
G54D51*
X367540Y125600D03*
Y123400D03*
X370040Y125600D03*
Y123400D03*
X373540Y125600D03*
Y123400D03*
X376040Y125600D03*
Y123400D03*
X379540Y125600D03*
Y123400D03*
X382040Y125600D03*
Y123400D03*
X385540Y125600D03*
Y123400D03*
X388040Y125600D03*
Y123400D03*
X391540Y125600D03*
Y123400D03*
X394040Y125600D03*
Y123400D03*
X397540Y125667D03*
Y123467D03*
X400040Y125667D03*
Y123467D03*
X403540Y125600D03*
Y123400D03*
X406040Y125600D03*
Y123400D03*
X409540Y125600D03*
Y123400D03*
X412040Y125600D03*
Y123400D03*
X403055Y326100D03*
Y323900D03*
X444255Y394600D03*
Y392400D03*
X436355Y394200D03*
Y392000D03*
X450455Y364800D03*
Y362600D03*
X453855Y381100D03*
Y378900D03*
Y388400D03*
Y386200D03*
X451355Y395000D03*
Y392800D03*
X463535Y354910D03*
Y352710D03*
X482000Y133100D03*
Y130900D03*
X484929Y133100D03*
Y130900D03*
X482055Y375100D03*
Y372900D03*
X488555Y388100D03*
Y385900D03*
X489055Y396100D03*
Y393900D03*
X488555Y412100D03*
Y409900D03*
G54D25*
X87388Y853252D03*
X123104Y796720D03*
Y800720D03*
X390729Y170500D03*
Y174000D03*
X390300Y197200D03*
Y200600D03*
X390800Y190000D03*
X401229Y170500D03*
X401329Y165000D03*
X401229Y177000D03*
Y183500D03*
Y190000D03*
X399359Y215180D03*
X409855Y338850D03*
X410755Y372000D03*
X415840Y139000D03*
X428529Y205200D03*
X428469Y208670D03*
X423539Y214650D03*
X415929Y214680D03*
X425355Y372500D03*
X427078Y824500D03*
X426978Y864000D03*
X438629Y151710D03*
X437679Y158620D03*
X437729Y170860D03*
X437819Y164850D03*
X437729Y177400D03*
X437929Y183800D03*
X438049Y202480D03*
X437729Y189750D03*
X438229Y196000D03*
X438039Y208870D03*
X459855Y326500D03*
X1010300Y70500D03*
X1063800Y120500D03*
X1163300Y704500D03*
X1170300Y685500D03*
X1170268Y695284D03*
Y689284D03*
X1179800Y701300D03*
X1170268Y700284D03*
X1358300Y456000D03*
G54D52*
X375040Y147400D03*
Y149600D03*
X374629Y171100D03*
Y173300D03*
X389540Y130400D03*
Y132600D03*
X387029Y152600D03*
Y154800D03*
X380769Y152240D03*
Y154440D03*
X409040Y143900D03*
Y146100D03*
X399055Y441400D03*
Y443600D03*
X413929Y131400D03*
Y133600D03*
X453555Y362600D03*
Y364800D03*
X453455Y398100D03*
Y400300D03*
X451255Y398100D03*
Y400300D03*
X475855Y352700D03*
Y354900D03*
X474555Y417900D03*
X469055Y415900D03*
Y418100D03*
X474555Y420100D03*
X479055Y352900D03*
Y355100D03*
X482555Y378400D03*
Y380600D03*
X483055Y393900D03*
Y396100D03*
X481055Y405900D03*
Y408100D03*
X782324Y342948D03*
Y345148D03*
X778824Y342948D03*
Y345148D03*
G54D43*
X312000Y289300D03*
X321500Y81800D03*
X326000D03*
X317000D03*
X329500Y290800D03*
X341000Y112840D03*
X353500Y11800D03*
X393929Y221300D03*
X394555Y431300D03*
X402929Y230300D03*
X406929D03*
X399555Y431300D03*
X425940Y151600D03*
X413429Y236800D03*
X426523Y323583D03*
X425278Y805300D03*
X435055Y284300D03*
X430523Y323583D03*
X431778Y805300D03*
X437778Y875800D03*
X431278D03*
X456278Y805300D03*
X460778Y875800D03*
X462778Y805300D03*
X467278Y875800D03*
X509555Y416800D03*
X552555Y341800D03*
X556555D03*
X651000Y448800D03*
X645500Y472300D03*
X1137500Y652800D03*
X1166000Y644800D03*
X1153000D03*
X1158000D03*
X1162000D03*
X1213000Y630800D03*
X1209000D03*
X1217000D03*
X1260500Y637800D03*
X1277000Y687300D03*
X1273000Y705800D03*
X1281000Y716300D03*
X1277000Y724300D03*
X1358584Y280968D03*
X1376300Y281000D03*
X1380300D03*
X1384500Y319300D03*
G54D16*
X47476Y393479D03*
X43976D03*
X62976D03*
X56976D03*
X66476D03*
X53476D03*
X75476D03*
X71976D03*
X165795Y303909D03*
X179295D03*
X175295D03*
X169795D03*
X213795Y300409D03*
X209795D03*
X203795D03*
X200295D03*
X269678Y962200D03*
X273678D03*
X334000Y80700D03*
X346000Y112740D03*
X349000Y11700D03*
X361500D03*
X358000D03*
X360819Y207240D03*
X371239Y188370D03*
X371299Y195940D03*
X376929Y205200D03*
X386300Y161200D03*
X409429Y157200D03*
X399429D03*
X402929D03*
X422200Y157000D03*
X418714Y157050D03*
X415314D03*
X450678Y808700D03*
X507055Y408700D03*
X733716Y131984D03*
X730216D03*
X1006500Y74700D03*
X1277000Y698200D03*
X1273000Y716200D03*
G54D34*
X297800Y98500D03*
X305800D03*
X346380Y179800D03*
X361729Y199389D03*
X379800Y901500D03*
Y906000D03*
X403800Y889500D03*
Y893500D03*
Y905500D03*
Y897500D03*
Y909500D03*
Y901500D03*
X426800Y241000D03*
Y245000D03*
X425300Y314500D03*
X414823Y326283D03*
X423578Y828500D03*
Y837500D03*
Y842000D03*
Y833000D03*
Y846500D03*
Y851000D03*
Y860000D03*
Y855500D03*
X443340Y118000D03*
X433683Y145701D03*
X446229Y113500D03*
X448229Y171500D03*
Y184500D03*
Y180000D03*
X464729Y104000D03*
X467729Y122000D03*
X474300Y140000D03*
X470729Y149000D03*
Y153500D03*
X470800Y144500D03*
X471300Y157500D03*
X470800Y162000D03*
X466300Y169000D03*
Y176000D03*
X476331Y190291D03*
X462300Y286500D03*
X488078Y857000D03*
Y852500D03*
Y861500D03*
X508229Y135000D03*
X511229Y151000D03*
X524229Y129000D03*
X776800Y968500D03*
X1006800Y66500D03*
X1035800Y145500D03*
X1060300Y124500D03*
X1085300Y640000D03*
X1077800D03*
X1132138Y688864D03*
X1222300Y722500D03*
X1248300Y715500D03*
Y719500D03*
X1250300Y641000D03*
Y647000D03*
X1257800D03*
X1250300Y657000D03*
Y651000D03*
Y661000D03*
Y667000D03*
Y675500D03*
Y679500D03*
Y691500D03*
Y695500D03*
Y699500D03*
Y703500D03*
Y707500D03*
Y711500D03*
X1255800Y715500D03*
X1340800Y399500D03*
G54D61*
X545079Y290355D03*
Y315945D03*
X560829Y290355D03*
X556889Y298230D03*
X552954Y290355D03*
X549014Y298230D03*
X560829Y315945D03*
X556889Y308070D03*
X552954Y315945D03*
X549014Y308070D03*
X576574Y290355D03*
X572639Y298230D03*
X568699Y290355D03*
X564764Y298230D03*
X576574Y315945D03*
X572639Y308070D03*
X568699Y315945D03*
X564764Y308070D03*
X592324Y290355D03*
X588384Y298230D03*
X584449Y290355D03*
X580514Y298230D03*
X592324Y315945D03*
X588384Y308070D03*
X584449Y315945D03*
X580514Y308070D03*
X608069Y290355D03*
X604134Y298230D03*
X600199Y290355D03*
X596259Y298230D03*
X608069Y315945D03*
X604134Y308070D03*
X600199Y315945D03*
X596259Y308070D03*
X627754Y298230D03*
X623819Y290355D03*
X619884Y298230D03*
X615944Y290355D03*
X612009Y298230D03*
X627754Y308070D03*
X623819Y315945D03*
X619884Y308070D03*
X615944Y315945D03*
X612009Y308070D03*
X643504Y298230D03*
X639569Y290355D03*
X635629Y298230D03*
X631694Y290355D03*
X643504Y308070D03*
X639569Y315945D03*
X635629Y308070D03*
X631694Y315945D03*
X659254Y298230D03*
X655314Y290355D03*
X651379Y298230D03*
X647439Y290355D03*
X659254Y308070D03*
X655314Y315945D03*
X651379Y308070D03*
X647439Y315945D03*
X674999Y298230D03*
X671064Y290355D03*
X667124Y298230D03*
X663189Y290355D03*
X674999Y308070D03*
X671064Y315945D03*
X667124Y308070D03*
X663189Y315945D03*
X690749Y298230D03*
X686809Y290355D03*
X682874Y298230D03*
X678939Y290355D03*
X690749Y308070D03*
X686809Y315945D03*
X682874Y308070D03*
X678939Y315945D03*
X706494Y298230D03*
X702559Y290355D03*
X698624Y298230D03*
X694684Y290355D03*
X706494Y308070D03*
X702559Y315945D03*
X698624Y308070D03*
X694684Y315945D03*
X726179Y290355D03*
X722244Y298230D03*
X718309Y290355D03*
X714369Y298230D03*
X710434Y290355D03*
X726179Y315945D03*
X722244Y308070D03*
X718309Y315945D03*
X714369Y308070D03*
X710434Y315945D03*
X741929Y290355D03*
X737994Y298230D03*
X734054Y290355D03*
X730119Y298230D03*
X741929Y315945D03*
X737994Y308070D03*
X734054Y315945D03*
X730119Y308070D03*
X757679Y290355D03*
X753739Y298230D03*
X749804Y290355D03*
X745864Y298230D03*
X757679Y315945D03*
X753739Y308070D03*
X749804Y315945D03*
X745864Y308070D03*
X773424Y290355D03*
X769489Y298230D03*
X765549Y290355D03*
X761614Y298230D03*
X773424Y315945D03*
X769489Y308070D03*
X765549Y315945D03*
X761614Y308070D03*
X789174Y290355D03*
X785234Y298230D03*
X781299Y290355D03*
X777364Y298230D03*
X789174Y315945D03*
X785234Y308070D03*
X781299Y315945D03*
X777364Y308070D03*
X804919Y290355D03*
X800984Y298230D03*
X797049Y290355D03*
X793109Y298230D03*
X804919Y315945D03*
X800984Y308070D03*
X797049Y315945D03*
X793109Y308070D03*
X820669Y290355D03*
X816734Y298230D03*
X812794Y290355D03*
X808859Y298230D03*
X820669Y315945D03*
X816734Y308070D03*
X812794Y315945D03*
X808859Y308070D03*
X840354Y298230D03*
X836419Y290355D03*
X832479Y298230D03*
X840354Y308070D03*
X836419Y315945D03*
X832479Y308070D03*
X856104Y298230D03*
X852164Y290355D03*
X848229Y298230D03*
X844289Y290355D03*
X856104Y308070D03*
X852164Y315945D03*
X848229Y308070D03*
X844289Y315945D03*
X871849Y298230D03*
X867914Y290355D03*
X863974Y298230D03*
X860039Y290355D03*
X871849Y308070D03*
X867914Y315945D03*
X863974Y308070D03*
X860039Y315945D03*
G54D70*
X678800Y466000D03*
X1347317Y533012D03*
Y525012D03*
G54D17*
X48700Y872500D03*
Y868500D03*
X340740Y193000D03*
X340629Y189000D03*
X340740Y197500D03*
X346700Y396000D03*
X362210Y179910D03*
X416700Y225000D03*
X441129Y113500D03*
X451629Y175500D03*
X470855Y308700D03*
X479700Y186231D03*
X479723Y334283D03*
X491478Y844000D03*
Y836000D03*
Y840000D03*
Y848500D03*
X527629Y124500D03*
X534700Y148500D03*
X780200Y973000D03*
X1039200Y141000D03*
X1081200Y667500D03*
Y679500D03*
Y675500D03*
Y671500D03*
Y683500D03*
X1069568Y681554D03*
X1081200Y695500D03*
Y687500D03*
Y691500D03*
Y699500D03*
Y711500D03*
Y707500D03*
Y703500D03*
Y723500D03*
Y719500D03*
Y715500D03*
Y727500D03*
X1082200Y736500D03*
X1089700Y630000D03*
X1091200Y655000D03*
X1091188Y650584D03*
X1171900Y679300D03*
X1225700Y727000D03*
Y718500D03*
Y735500D03*
Y731000D03*
X1261200Y651000D03*
Y657000D03*
Y661000D03*
X1253700Y671000D03*
X1261200Y667500D03*
X1253700Y687500D03*
Y683500D03*
G54D44*
X323060Y285250D03*
X317940D03*
Y291750D03*
X320500D03*
X323060D03*
G54D62*
X590315Y9134D03*
Y19134D03*
X649527Y9134D03*
Y19134D03*
Y29134D03*
G54D80*
X1272441Y7087D03*
X1299213D03*
G54D26*
X114174Y1009860D03*
X110234D03*
X133859D03*
X129919D03*
X125984D03*
X122049D03*
X118109D03*
X149604D03*
X145669D03*
X165354D03*
X161419D03*
X157479D03*
X153544D03*
X181104D03*
X177164D03*
X173229D03*
X169289D03*
X279528D03*
X275588D03*
X271653D03*
X267718D03*
X295273D03*
X291338D03*
X287403D03*
X283463D03*
X311023D03*
X307088D03*
X303148D03*
X299213D03*
X330708D03*
X326773D03*
X322833D03*
X318898D03*
X314958D03*
X346458D03*
X342518D03*
X338583D03*
X334643D03*
X362203D03*
X358268D03*
X354333D03*
X350393D03*
X377953D03*
X374018D03*
X370078D03*
X366143D03*
X393703D03*
X389763D03*
X385828D03*
X381888D03*
X409448D03*
X405513D03*
X401573D03*
X397638D03*
X429133D03*
X425198D03*
X421258D03*
X417323D03*
X413388D03*
X444883D03*
X440943D03*
X437008D03*
X433073D03*
X460628D03*
X456693D03*
X452758D03*
X448818D03*
X476378D03*
X472443D03*
X468503D03*
X464568D03*
X492128D03*
X488188D03*
X484253D03*
X480313D03*
X507873D03*
X503938D03*
X499998D03*
X496063D03*
X527558D03*
X523623D03*
X519683D03*
X515748D03*
X511813D03*
X543308D03*
X539368D03*
X535433D03*
X531498D03*
X559053D03*
X555118D03*
X574803D03*
X570868D03*
X566928D03*
X562993D03*
X590553D03*
X586613D03*
X582678D03*
X578738D03*
X723623D03*
X719683D03*
X739368D03*
X735433D03*
X731498D03*
X727558D03*
X755118D03*
X743308D03*
X770868D03*
X766928D03*
X762993D03*
X759053D03*
X790553D03*
X786613D03*
X782678D03*
X778738D03*
X774803D03*
G54D53*
X402953Y23622D03*
X413189D03*
X423425D03*
G54D71*
X945197Y380000D03*
X968819D03*
G54D35*
X314500Y71200D03*
X307500Y288700D03*
X319500Y71200D03*
X332500Y68700D03*
X1031500Y63700D03*
X1036500D03*
X1041500D03*
X1046500D03*
X1051500D03*
X1124800Y804200D03*
X1131300D03*
X1142000Y799700D03*
X1212500Y197700D03*
X1204390Y703400D03*
G54D18*
X45300Y872500D03*
Y868500D03*
X337340Y193000D03*
X337229Y189000D03*
X337340Y197500D03*
X343300Y396000D03*
X358810Y179910D03*
X413300Y225000D03*
X437729Y113500D03*
X448229Y175500D03*
X476300Y186231D03*
X467455Y308700D03*
X476323Y334283D03*
X488078Y844000D03*
Y836000D03*
Y840000D03*
Y848500D03*
X524229Y124500D03*
X531300Y148500D03*
X776800Y973000D03*
X1035800Y141000D03*
X1066168Y681554D03*
X1077800Y667500D03*
Y679500D03*
Y675500D03*
Y671500D03*
Y683500D03*
Y695500D03*
Y687500D03*
Y691500D03*
Y699500D03*
Y711500D03*
Y707500D03*
Y703500D03*
Y723500D03*
Y719500D03*
Y715500D03*
Y727500D03*
X1078800Y736500D03*
X1086300Y630000D03*
X1087800Y655000D03*
X1087788Y650584D03*
X1168500Y679300D03*
X1222300Y727000D03*
Y718500D03*
Y735500D03*
Y731000D03*
X1257800Y651000D03*
Y657000D03*
Y661000D03*
X1250300Y671000D03*
X1257800Y667500D03*
X1250300Y687500D03*
Y683500D03*
G54D81*
X1368000Y457750D03*
G54D54*
X439029Y100000D03*
Y108000D03*
X447829Y104000D03*
X494329Y149500D03*
X485529Y145500D03*
Y153500D03*
G54D45*
X332086Y408858D03*
X355708Y96456D03*
X450196Y257874D03*
X572243Y337992D03*
G54D72*
X1008268Y244094D03*
Y411417D03*
X1227166Y155511D03*
X1227165Y411417D03*
G54D36*
X299750Y88000D03*
X307250Y84125D03*
Y91875D03*
X343250Y287625D03*
X335750Y291500D03*
X343250Y295375D03*
X510179Y125500D03*
X517679Y121625D03*
Y129375D03*
G54D63*
X585315Y44134D03*
X654527D03*
G54D27*
X121890Y269528D03*
X131890D03*
X141890D03*
X1346396Y21656D03*
X1338526D03*
X1346396Y29526D03*
X1338526D03*
X1362146Y21656D03*
X1354271D03*
X1362146Y29526D03*
X1354271D03*
X1377896Y21656D03*
X1370021D03*
X1377896Y29526D03*
X1370021D03*
X1385766Y21656D03*
Y29526D03*
G54D46*
X343929Y215450D03*
X356929Y215700D03*
X364909Y190119D03*
X365429Y215450D03*
X394029Y196100D03*
X385429Y219700D03*
X410729Y196200D03*
X407214Y196250D03*
X403109Y215980D03*
X438055Y319200D03*
X461929Y180200D03*
X451055Y378200D03*
Y385700D03*
X455778Y872200D03*
X471429Y126200D03*
X489555Y427700D03*
X678400Y398800D03*
X731716Y109484D03*
X735216D03*
X1149268Y675884D03*
X1144768Y677484D03*
X1157000Y677200D03*
X1154300Y802700D03*
X1160300Y801200D03*
X1165300D03*
X1170300D03*
X1200370Y704450D03*
X1217000Y198700D03*
X1220500D03*
X1273236Y687078D03*
X1277000Y705700D03*
X1273000Y724200D03*
X1292500Y405700D03*
X1312500Y607700D03*
X1306500Y645200D03*
X1379500Y319200D03*
G54D37*
X314500Y76800D03*
X307500Y294300D03*
X319500Y76800D03*
X332500Y74300D03*
X1031500Y69300D03*
X1036500D03*
X1041500D03*
X1046500D03*
X1051500D03*
X1124800Y809800D03*
X1131300D03*
X1142000Y805300D03*
X1212500Y203300D03*
X1204390Y709000D03*
G54D19*
X43520Y910988D03*
X48020D03*
X52520D03*
X57020D03*
X61520D03*
X66020D03*
X99804Y913020D03*
X103804D03*
X107804D03*
X111804D03*
X115804D03*
X119804D03*
X123804D03*
X127804D03*
X131804D03*
X135804D03*
X313000Y89300D03*
X330000Y84300D03*
X314453Y245152D03*
X344040Y207300D03*
X357040D03*
X348540D03*
X353040D03*
X351000Y392800D03*
X373200Y179840D03*
X371429Y203800D03*
X380829Y187900D03*
X393000Y940800D03*
X406555Y323300D03*
X405000Y940800D03*
X409000D03*
X397000D03*
X401000D03*
X425278Y808800D03*
X413000Y940800D03*
X417000D03*
X429940Y151600D03*
X444055Y295300D03*
X431778Y808800D03*
X431278Y872300D03*
X437778D03*
X456278Y808800D03*
X460778Y872300D03*
X462778Y808800D03*
X467278Y872300D03*
X544178Y964800D03*
X548555Y341800D03*
X554955Y368200D03*
X558955D03*
X641000Y472300D03*
X646500Y448800D03*
X678500Y406800D03*
X787000Y411300D03*
X1010500Y74800D03*
X1178500Y644300D03*
X1281000Y687300D03*
Y705800D03*
X1273000Y698300D03*
X1281000D03*
X1277000Y716300D03*
X1281000Y724300D03*
X1292500Y413300D03*
X1350084Y280968D03*
X1372300Y281000D03*
X1384300D03*
G54D64*
X600925Y44134D03*
X638917D03*
G54D55*
X437478Y845016D03*
Y843047D03*
Y848953D03*
Y846984D03*
X473078Y843047D03*
Y845016D03*
Y846984D03*
Y848953D03*
G54D73*
X1015740Y50500D03*
X1012000D03*
X1008260D03*
Y59500D03*
X1015740D03*
G54D82*
X1368000Y455250D03*
G54D28*
X153937Y238898D03*
Y246772D03*
Y260551D03*
X224015Y234961D03*
Y246772D03*
Y260551D03*
G54D83*
G01X-245081Y-422119D02*
G02I-12000J0D01*
G01X-250231D02*
G02I-6850J0D01*
G01X-241081D02*
X-273081D01*
G01X-257081Y-438119D02*
Y-406119D01*
G01X-241081Y-438119D02*
Y-518119D01*
G01D02*
X1034819D01*
G01X-241081Y-473619D02*
X1034819D01*
G01X-241081Y-438119D02*
X1034819D01*
G01X247319D02*
Y-518119D01*
G01X384819Y-438119D02*
Y-518119D01*
G01X499819Y-438119D02*
Y-518119D01*
G01X667319Y-438119D02*
Y-518119D01*
G01X837319Y-438119D02*
Y-518119D01*
G01X1034819Y-438119D02*
Y-518119D01*
G01X1066819Y-422119D02*
X1034819D01*
G01X1050819Y-438119D02*
Y-406119D01*
G01X1062819Y-422119D02*
G02I-12000J0D01*
G01X1057669D02*
G02I-6850J0D01*
G54D47*
X343929Y219050D03*
X356929Y219300D03*
X364909Y193719D03*
X365429Y219050D03*
X394029Y199700D03*
X385429Y223300D03*
X410729Y199800D03*
X407214Y199850D03*
X403109Y219580D03*
X438055Y322800D03*
X461929Y183800D03*
X451055Y381800D03*
Y389300D03*
X455778Y875800D03*
X471429Y129800D03*
X489555Y431300D03*
X678400Y402400D03*
X731716Y113084D03*
X735216D03*
X1149268Y679484D03*
X1144768Y681084D03*
X1157000Y680800D03*
X1154300Y806300D03*
X1160300Y804800D03*
X1165300D03*
X1170300D03*
X1200370Y708050D03*
X1217000Y202300D03*
X1220500D03*
X1273236Y690678D03*
X1277000Y709300D03*
X1273000Y727800D03*
X1292500Y409300D03*
X1312500Y611300D03*
X1306500Y648800D03*
X1379500Y322800D03*
G54D74*
X1045000Y32598D03*
X1096732D03*
G54D56*
X439530Y839000D03*
X441498D03*
X443467D03*
Y853000D03*
X441498D03*
X439530D03*
X445435Y839000D03*
X447404D03*
X449372D03*
X451341D03*
X453309D03*
X455278D03*
X457247D03*
X459215D03*
X461184D03*
Y853000D03*
X459215D03*
X457247D03*
X455278D03*
X453309D03*
X451341D03*
X449372D03*
X447404D03*
X445435D03*
X463152Y839000D03*
X465121D03*
X467089D03*
X469058D03*
X471026D03*
Y853000D03*
X469058D03*
X467089D03*
X465121D03*
X463152D03*
G54D38*
X301200Y98500D03*
X309200D03*
X349780Y179800D03*
X365129Y199389D03*
X383200Y901500D03*
Y906000D03*
X407200Y889500D03*
Y893500D03*
Y905500D03*
Y897500D03*
Y909500D03*
Y901500D03*
X428700Y314500D03*
X418223Y326283D03*
X426978Y828500D03*
Y837500D03*
Y842000D03*
Y833000D03*
Y846500D03*
Y851000D03*
Y860000D03*
Y855500D03*
X437083Y145701D03*
X430200Y241000D03*
Y245000D03*
X446740Y118000D03*
X449629Y113500D03*
X451629Y171500D03*
Y184500D03*
Y180000D03*
X468129Y104000D03*
X471129Y122000D03*
X477700Y140000D03*
X474129Y149000D03*
Y153500D03*
X474200Y144500D03*
X474700Y157500D03*
X474200Y162000D03*
X469700Y169000D03*
Y176000D03*
X465700Y286500D03*
X479731Y190291D03*
X491478Y857000D03*
Y852500D03*
Y861500D03*
X511629Y135000D03*
X527629Y129000D03*
X514629Y151000D03*
X780200Y968500D03*
X1010200Y66500D03*
X1039200Y145500D03*
X1063700Y124500D03*
X1081200Y640000D03*
X1088700D03*
X1135538Y688864D03*
X1225700Y722500D03*
X1253700Y641000D03*
Y647000D03*
X1261200D03*
X1253700Y657000D03*
Y651000D03*
Y661000D03*
Y667000D03*
Y675500D03*
Y679500D03*
Y691500D03*
Y695500D03*
Y699500D03*
Y703500D03*
Y707500D03*
Y711500D03*
X1251700Y715500D03*
Y719500D03*
X1259200Y715500D03*
X1344200Y399500D03*
G54D65*
X599941Y70118D03*
X607933D03*
X595905Y80118D03*
X603897D03*
X611889D03*
X615925Y70118D03*
X623917D03*
X627953Y80118D03*
X631909Y70118D03*
X639901D03*
X635945Y80118D03*
X643937D03*
G54D29*
X195295Y301709D03*
X188295Y301209D03*
X195295Y307709D03*
X188295Y315209D03*
X184295Y305709D03*
X195795Y313709D03*
X189795Y308709D03*
X183795Y311709D03*
X483178Y861500D03*
X1379862Y108465D03*
Y119095D03*
G54D84*
G01X-185516Y-508119D02*
Y-490619D01*
G01X-176346D02*
Y-508119D01*
G01Y-499369D02*
X-185516D01*
G01X-163431Y-508119D02*
X-165178Y-507827D01*
X-166706Y-506661D01*
X-168016Y-504911D01*
X-168890Y-502869D01*
X-169326Y-500536D01*
Y-498202D01*
X-168890Y-495869D01*
X-168016Y-493827D01*
X-166706Y-492078D01*
X-165178Y-490911D01*
X-163431Y-490619D01*
X-161685Y-490911D01*
X-160156Y-492078D01*
X-158846Y-493827D01*
X-157972Y-495869D01*
X-157536Y-498202D01*
Y-500536D01*
X-157972Y-502869D01*
X-158846Y-504911D01*
X-160156Y-506661D01*
X-161685Y-507827D01*
X-163431Y-508119D01*
G01X-150953D02*
Y-490619D01*
X-140909Y-508119D01*
Y-490619D01*
G01X-124064Y-508119D02*
X-132798D01*
Y-490619D01*
X-124064D01*
G01X-127558Y-499077D02*
X-132798D01*
G01X-110931Y-508119D02*
Y-500244D01*
X-115298Y-490619D01*
G01X-106564D02*
X-110931Y-500244D01*
G01X-74185Y-498786D02*
X-73311Y-497911D01*
X-72656Y-496453D01*
X-72219Y-494410D01*
X-72656Y-492661D01*
X-73529Y-491494D01*
X-75058Y-490619D01*
X-80953D01*
Y-508119D01*
X-73748D01*
X-72219Y-506953D01*
X-71346Y-505202D01*
X-70909Y-503161D01*
X-71346Y-501119D01*
X-72656Y-499369D01*
X-74185Y-498786D01*
X-80953D01*
G01X-63890Y-508119D02*
X-58431Y-490619D01*
X-52972Y-508119D01*
G01X-54938Y-501994D02*
X-61925D01*
G01X-45734Y-508119D02*
Y-490619D01*
X-41368D01*
X-39621Y-491494D01*
X-38311Y-492661D01*
X-37219Y-494410D01*
X-36346Y-496453D01*
X-36128Y-499369D01*
X-36346Y-502286D01*
X-37219Y-504328D01*
X-38311Y-506078D01*
X-39621Y-507244D01*
X-41368Y-508119D01*
X-45734D01*
G01X-22121Y-499369D02*
X-17754D01*
Y-504619D01*
X-19064Y-506369D01*
X-20593Y-507536D01*
X-22776Y-508119D01*
X-24959Y-507536D01*
X-26488Y-506369D01*
X-27798Y-504619D01*
X-28671Y-502577D01*
X-29108Y-500244D01*
Y-498202D01*
X-28671Y-496453D01*
X-27798Y-494410D01*
X-26488Y-492661D01*
X-25178Y-491494D01*
X-23431Y-490619D01*
X-21903D01*
X-20156Y-491202D01*
X-18846Y-492369D01*
G01X-1564Y-508119D02*
X-10298D01*
Y-490619D01*
X-1564D01*
G01X-5058Y-499077D02*
X-10298D01*
G01X7202Y-508119D02*
Y-490619D01*
X12661D01*
X14407Y-491494D01*
X15499Y-492661D01*
X15936Y-494994D01*
X15499Y-497328D01*
X14189Y-498786D01*
X12661Y-499661D01*
X7202D01*
G01X12661D02*
X15936Y-508119D01*
G01X48315Y-498786D02*
X49189Y-497911D01*
X49844Y-496453D01*
X50281Y-494410D01*
X49844Y-492661D01*
X48971Y-491494D01*
X47442Y-490619D01*
X41547D01*
Y-508119D01*
X48752D01*
X50281Y-506953D01*
X51154Y-505202D01*
X51591Y-503161D01*
X51154Y-501119D01*
X49844Y-499369D01*
X48315Y-498786D01*
X41547D01*
G01X58610Y-508119D02*
X64069Y-490619D01*
X69528Y-508119D01*
G01X67562Y-501994D02*
X60575D01*
G01X76984Y-505786D02*
X78731Y-507244D01*
X80696Y-508119D01*
X82442D01*
X84189Y-507244D01*
X85499Y-505786D01*
X86154Y-503744D01*
X85717Y-501703D01*
X84626Y-499952D01*
X82661Y-498786D01*
X80041Y-498202D01*
X78512Y-497036D01*
X77857Y-494994D01*
X78294Y-492952D01*
X79386Y-491494D01*
X80914Y-490619D01*
X82442D01*
X83971Y-491202D01*
X85281Y-492661D01*
G01X103436Y-508119D02*
X94702D01*
Y-490619D01*
X103436D01*
G01X99942Y-499077D02*
X94702D01*
G01X118315Y-498786D02*
X119189Y-497911D01*
X119844Y-496453D01*
X120281Y-494410D01*
X119844Y-492661D01*
X118971Y-491494D01*
X117442Y-490619D01*
X111547D01*
Y-508119D01*
X118752D01*
X120281Y-506953D01*
X121154Y-505202D01*
X121591Y-503161D01*
X121154Y-501119D01*
X119844Y-499369D01*
X118315Y-498786D01*
X111547D01*
G01X134069Y-508119D02*
X132322Y-507827D01*
X130794Y-506661D01*
X129484Y-504911D01*
X128610Y-502869D01*
X128174Y-500536D01*
Y-498202D01*
X128610Y-495869D01*
X129484Y-493827D01*
X130794Y-492078D01*
X132322Y-490911D01*
X134069Y-490619D01*
X135815Y-490911D01*
X137344Y-492078D01*
X138654Y-493827D01*
X139528Y-495869D01*
X139964Y-498202D01*
Y-500536D01*
X139528Y-502869D01*
X138654Y-504911D01*
X137344Y-506661D01*
X135815Y-507827D01*
X134069Y-508119D01*
G01X146110D02*
X151569Y-490619D01*
X157028Y-508119D01*
G01X155062Y-501994D02*
X148075D01*
G01X164702Y-508119D02*
Y-490619D01*
X170161D01*
X171907Y-491494D01*
X172999Y-492661D01*
X173436Y-494994D01*
X172999Y-497328D01*
X171689Y-498786D01*
X170161Y-499661D01*
X164702D01*
G01X170161D02*
X173436Y-508119D01*
G01X181766D02*
Y-490619D01*
X186132D01*
X187879Y-491494D01*
X189189Y-492661D01*
X190281Y-494410D01*
X191154Y-496453D01*
X191372Y-499369D01*
X191154Y-502286D01*
X190281Y-504328D01*
X189189Y-506078D01*
X187879Y-507244D01*
X186132Y-508119D01*
X181766D01*
G01X-37858Y-463119D02*
Y-445619D01*
X-32181Y-460202D01*
X-26504Y-445619D01*
Y-463119D01*
G01X-14681D02*
X-15991Y-462827D01*
X-17301Y-461661D01*
X-18175Y-459619D01*
X-18611Y-457286D01*
X-18175Y-454952D01*
X-17301Y-452911D01*
X-15991Y-451744D01*
X-14681Y-451453D01*
X-13371Y-451744D01*
X-12061Y-452911D01*
X-11188Y-454952D01*
X-10969Y-457286D01*
X-11188Y-459619D01*
X-12061Y-461661D01*
X-13371Y-462827D01*
X-14681Y-463119D01*
G01X6749Y-445619D02*
Y-463119D01*
G01Y-460495D02*
X5876Y-461953D01*
X4565Y-462827D01*
X3037Y-463119D01*
X1291Y-462536D01*
X-19Y-461078D01*
X-893Y-459328D01*
X-1111Y-457286D01*
X-893Y-455244D01*
X-19Y-453494D01*
X1291Y-452036D01*
X3037Y-451453D01*
X4565Y-451744D01*
X5657Y-452328D01*
X6749Y-453494D01*
G01X17044Y-455244D02*
X24031D01*
X23376Y-453202D01*
X22284Y-452036D01*
X20756Y-451453D01*
X19227Y-451744D01*
X17917Y-452619D01*
X17044Y-454661D01*
X16607Y-456411D01*
Y-458161D01*
X17044Y-459911D01*
X18136Y-461661D01*
X19446Y-462827D01*
X20974Y-463119D01*
X22502Y-462536D01*
X24031Y-460786D01*
G01X37819Y-463119D02*
Y-445619D01*
G01X281019Y-508119D02*
Y-490619D01*
X278399Y-494119D01*
G01Y-508119D02*
X283639D01*
G01X293716Y-504619D02*
X295025Y-506661D01*
X296772Y-507827D01*
X298737Y-508119D01*
X300484Y-507827D01*
X302231Y-506369D01*
X303322Y-504619D01*
X303541Y-502869D01*
X303104Y-500828D01*
X301576Y-499369D01*
X300047Y-498786D01*
X298082D01*
G01X300047D02*
X301357Y-497911D01*
X302449Y-496453D01*
X302886Y-494703D01*
X302449Y-492952D01*
X301357Y-491494D01*
X299392Y-490619D01*
X297427Y-490911D01*
X295462Y-492078D01*
G01X312307Y-506078D02*
X313836Y-507536D01*
X315582Y-508119D01*
X317329Y-507536D01*
X318857Y-505786D01*
X319949Y-503161D01*
X320386Y-500536D01*
Y-497328D01*
X319949Y-494703D01*
X318857Y-492369D01*
X317547Y-491202D01*
X316019Y-490619D01*
X314272Y-491202D01*
X312962Y-492369D01*
X312089Y-494119D01*
X311652Y-496453D01*
X312089Y-498494D01*
X313181Y-500536D01*
X314491Y-501703D01*
X316019Y-501994D01*
X317765Y-501411D01*
X319076Y-499952D01*
X320386Y-497328D01*
G01X336139Y-508119D02*
Y-490619D01*
X328060Y-503161D01*
X338978D01*
G01X351019Y-508119D02*
X352547Y-507827D01*
X354294Y-506953D01*
X355386Y-505495D01*
X355822Y-503452D01*
X355386Y-501411D01*
X354076Y-499661D01*
X352111Y-498786D01*
X349927D01*
X348617Y-498202D01*
X347525Y-496744D01*
X347089Y-494703D01*
X347744Y-492661D01*
X349272Y-491202D01*
X351019Y-490619D01*
X352765Y-491202D01*
X354294Y-492661D01*
X354949Y-494703D01*
X354512Y-496744D01*
X353421Y-498202D01*
X352111Y-498786D01*
X349927D01*
X347962Y-499661D01*
X346652Y-501411D01*
X346216Y-503452D01*
X346652Y-505495D01*
X347744Y-506953D01*
X349491Y-507827D01*
X351019Y-508119D01*
G01X267902Y-463119D02*
Y-445619D01*
X273142D01*
X274889Y-446494D01*
X276199Y-448536D01*
X276636Y-450869D01*
X276199Y-453202D01*
X275107Y-454952D01*
X273142Y-455828D01*
X267902D01*
G01X294572Y-447078D02*
X293262Y-446202D01*
X291734Y-445619D01*
X289987D01*
X288022Y-446494D01*
X286494Y-447952D01*
X285402Y-449703D01*
X284529Y-452619D01*
X284310Y-455244D01*
X284747Y-457869D01*
X285402Y-459619D01*
X286712Y-461369D01*
X288241Y-462536D01*
X289769Y-463119D01*
X291297D01*
X292826Y-462536D01*
X294136Y-461661D01*
X295228Y-460495D01*
G01X309015Y-453786D02*
X309889Y-452911D01*
X310544Y-451453D01*
X310981Y-449410D01*
X310544Y-447661D01*
X309671Y-446494D01*
X308142Y-445619D01*
X302247D01*
Y-463119D01*
X309452D01*
X310981Y-461953D01*
X311854Y-460202D01*
X312291Y-458161D01*
X311854Y-456119D01*
X310544Y-454369D01*
X309015Y-453786D01*
X302247D01*
G01X318219Y-468952D02*
X331319D01*
G01X337247Y-463119D02*
Y-445619D01*
X347291Y-463119D01*
Y-445619D01*
G01X359769Y-463119D02*
X358022Y-462827D01*
X356494Y-461661D01*
X355184Y-459911D01*
X354310Y-457869D01*
X353874Y-455536D01*
Y-453202D01*
X354310Y-450869D01*
X355184Y-448827D01*
X356494Y-447078D01*
X358022Y-445911D01*
X359769Y-445619D01*
X361515Y-445911D01*
X363044Y-447078D01*
X364354Y-448827D01*
X365228Y-450869D01*
X365664Y-453202D01*
Y-455536D01*
X365228Y-457869D01*
X364354Y-459911D01*
X363044Y-461661D01*
X361515Y-462827D01*
X359769Y-463119D01*
G01X410610Y-445619D02*
X416069Y-463119D01*
X421528Y-445619D01*
G01X437936Y-463119D02*
X429202D01*
Y-445619D01*
X437936D01*
G01X434442Y-454077D02*
X429202D01*
G01X446702Y-463119D02*
Y-445619D01*
X452161D01*
X453907Y-446494D01*
X454999Y-447661D01*
X455436Y-449994D01*
X454999Y-452328D01*
X453689Y-453786D01*
X452161Y-454661D01*
X446702D01*
G01X452161D02*
X455436Y-463119D01*
G01X468569Y-463702D02*
X468132Y-463411D01*
Y-462827D01*
X468569Y-462536D01*
X469006Y-462827D01*
Y-463411D01*
X468569Y-463702D01*
G01X433569Y-508119D02*
Y-490619D01*
X430949Y-494119D01*
G01Y-508119D02*
X436189D01*
G01X452815Y-498786D02*
X453689Y-497911D01*
X454344Y-496453D01*
X454781Y-494410D01*
X454344Y-492661D01*
X453471Y-491494D01*
X451942Y-490619D01*
X446047D01*
Y-508119D01*
X453252D01*
X454781Y-506953D01*
X455654Y-505202D01*
X456091Y-503161D01*
X455654Y-501119D01*
X454344Y-499369D01*
X452815Y-498786D01*
X446047D01*
G01X616773D02*
X615899Y-497911D01*
X615244Y-496453D01*
X614807Y-494410D01*
X615244Y-492661D01*
X616117Y-491494D01*
X617646Y-490619D01*
X623541D01*
Y-508119D01*
X616336D01*
X614807Y-506953D01*
X613934Y-505202D01*
X613497Y-503161D01*
X613934Y-501119D01*
X615244Y-499369D01*
X616773Y-498786D01*
X623541D01*
G01X606696Y-508119D02*
Y-490619D01*
X601019Y-505202D01*
X595342Y-490619D01*
Y-508119D01*
G01X588978D02*
X583519Y-490619D01*
X578060Y-508119D01*
G01X580026Y-501994D02*
X587013D01*
G01X570604Y-505786D02*
X568857Y-507244D01*
X566892Y-508119D01*
X565146D01*
X563399Y-507244D01*
X562089Y-505786D01*
X561434Y-503744D01*
X561871Y-501703D01*
X562962Y-499952D01*
X564927Y-498786D01*
X567547Y-498202D01*
X569076Y-497036D01*
X569731Y-494994D01*
X569294Y-492952D01*
X568202Y-491494D01*
X566674Y-490619D01*
X565146D01*
X563617Y-491202D01*
X562307Y-492661D01*
G01X553322Y-508119D02*
Y-490619D01*
G01X545026D02*
X553322Y-501411D01*
G01X543716Y-508119D02*
X549611Y-496453D01*
G01X544152Y-445619D02*
Y-463119D01*
X552886D01*
G01X569949D02*
Y-451453D01*
G01Y-453494D02*
X569076Y-452328D01*
X567765Y-451744D01*
X566237Y-451453D01*
X564709Y-452036D01*
X563399Y-453202D01*
X562525Y-454952D01*
X562089Y-457286D01*
X562525Y-459619D01*
X563399Y-461369D01*
X564709Y-462536D01*
X566237Y-463119D01*
X567765Y-462827D01*
X569076Y-461953D01*
X569949Y-460786D01*
G01X578934Y-468369D02*
X580244Y-468952D01*
X581991Y-468369D01*
X583082Y-467203D01*
X583956Y-465744D01*
X585265Y-461078D01*
X588104Y-451453D01*
G01X581117D02*
X585265Y-461078D01*
G01X597744Y-455244D02*
X604731D01*
X604076Y-453202D01*
X602984Y-452036D01*
X601456Y-451453D01*
X599927Y-451744D01*
X598617Y-452619D01*
X597744Y-454661D01*
X597307Y-456411D01*
Y-458161D01*
X597744Y-459911D01*
X598836Y-461661D01*
X600146Y-462827D01*
X601674Y-463119D01*
X603202Y-462536D01*
X604731Y-460786D01*
G01X615462Y-463119D02*
Y-451453D01*
G01Y-453786D02*
X616554Y-452619D01*
X617646Y-451744D01*
X619174Y-451453D01*
X620265Y-451744D01*
X621576Y-452619D01*
G01X686702Y-490619D02*
Y-508119D01*
X695436D01*
G01X703984Y-513369D02*
X705294Y-513952D01*
X707041Y-513369D01*
X708132Y-512203D01*
X709006Y-510744D01*
X710315Y-506078D01*
X713154Y-496453D01*
G01X706167D02*
X710315Y-506078D01*
G01X722357Y-508119D02*
Y-496453D01*
G01Y-499369D02*
X723231Y-497911D01*
X724541Y-496744D01*
X726287Y-496453D01*
X727815Y-496744D01*
X729126Y-497911D01*
X729781Y-499952D01*
Y-508119D01*
G01X739857D02*
Y-496453D01*
G01Y-499369D02*
X740731Y-497911D01*
X742041Y-496744D01*
X743787Y-496453D01*
X745315Y-496744D01*
X746626Y-497911D01*
X747281Y-499952D01*
Y-508119D01*
G01X774202Y-490619D02*
Y-508119D01*
X782936D01*
G01X796069Y-496453D02*
Y-508119D01*
G01Y-491786D02*
X795632Y-491494D01*
Y-490911D01*
X796069Y-490619D01*
X796506Y-490911D01*
Y-491494D01*
X796069Y-491786D01*
G01X809857Y-496453D02*
Y-504619D01*
X810731Y-506661D01*
X812041Y-507827D01*
X813569Y-508119D01*
X815097Y-507827D01*
X816407Y-506661D01*
X817281Y-504619D01*
G01Y-508119D02*
Y-496453D01*
G01X686266Y-463119D02*
Y-445619D01*
X690632D01*
X692379Y-446494D01*
X693689Y-447661D01*
X694781Y-449410D01*
X695654Y-451453D01*
X695872Y-454369D01*
X695654Y-457286D01*
X694781Y-459328D01*
X693689Y-461078D01*
X692379Y-462244D01*
X690632Y-463119D01*
X686266D01*
G01X705294Y-455244D02*
X712281D01*
X711626Y-453202D01*
X710534Y-452036D01*
X709006Y-451453D01*
X707477Y-451744D01*
X706167Y-452619D01*
X705294Y-454661D01*
X704857Y-456411D01*
Y-458161D01*
X705294Y-459911D01*
X706386Y-461661D01*
X707696Y-462827D01*
X709224Y-463119D01*
X710752Y-462536D01*
X712281Y-460786D01*
G01X722794Y-461078D02*
X723886Y-462244D01*
X725414Y-463119D01*
X726724D01*
X728034Y-462536D01*
X728907Y-461661D01*
X729344Y-460495D01*
X729126Y-458744D01*
X728252Y-457869D01*
X724322Y-456119D01*
X723449Y-454077D01*
X723886Y-452619D01*
X724759Y-451744D01*
X726069Y-451453D01*
X727379Y-451744D01*
X728689Y-452619D01*
G01X743569Y-451453D02*
Y-463119D01*
G01Y-446786D02*
X743132Y-446494D01*
Y-445911D01*
X743569Y-445619D01*
X744006Y-445911D01*
Y-446494D01*
X743569Y-446786D01*
G01X758012Y-467494D02*
X759541Y-468661D01*
X761287Y-468952D01*
X762815Y-468661D01*
X764126Y-467203D01*
X764999Y-465161D01*
Y-451453D01*
G01Y-453786D02*
X764126Y-452619D01*
X762815Y-451744D01*
X761287Y-451453D01*
X759541Y-452036D01*
X758449Y-453202D01*
X757575Y-455244D01*
X757139Y-457286D01*
X757357Y-459036D01*
X758231Y-461078D01*
X759541Y-462536D01*
X761287Y-463119D01*
X762597Y-462827D01*
X764126Y-461661D01*
X764999Y-460495D01*
G01X774857Y-463119D02*
Y-451453D01*
G01Y-454369D02*
X775731Y-452911D01*
X777041Y-451744D01*
X778787Y-451453D01*
X780315Y-451744D01*
X781626Y-452911D01*
X782281Y-454952D01*
Y-463119D01*
G01X792794Y-455244D02*
X799781D01*
X799126Y-453202D01*
X798034Y-452036D01*
X796506Y-451453D01*
X794977Y-451744D01*
X793667Y-452619D01*
X792794Y-454661D01*
X792357Y-456411D01*
Y-458161D01*
X792794Y-459911D01*
X793886Y-461661D01*
X795196Y-462827D01*
X796724Y-463119D01*
X798252Y-462536D01*
X799781Y-460786D01*
G01X810512Y-463119D02*
Y-451453D01*
G01Y-453786D02*
X811604Y-452619D01*
X812696Y-451744D01*
X814224Y-451453D01*
X815315Y-451744D01*
X816626Y-452619D01*
G01X857269Y-508119D02*
Y-490619D01*
X854649Y-494119D01*
G01Y-508119D02*
X859889D01*
G01X874769D02*
Y-490619D01*
X872149Y-494119D01*
G01Y-508119D02*
X877389D01*
G01X888339Y-508702D02*
X896199Y-490619D01*
G01X909769Y-508119D02*
Y-490619D01*
X907149Y-494119D01*
G01Y-508119D02*
X912389D01*
G01X922466Y-504619D02*
X923775Y-506661D01*
X925522Y-507827D01*
X927487Y-508119D01*
X929234Y-507827D01*
X930981Y-506369D01*
X932072Y-504619D01*
X932291Y-502869D01*
X931854Y-500828D01*
X930326Y-499369D01*
X928797Y-498786D01*
X926832D01*
G01X928797D02*
X930107Y-497911D01*
X931199Y-496453D01*
X931636Y-494703D01*
X931199Y-492952D01*
X930107Y-491494D01*
X928142Y-490619D01*
X926177Y-490911D01*
X924212Y-492078D01*
G01X940839Y-508702D02*
X948699Y-490619D01*
G01X958121Y-493536D02*
X959431Y-491786D01*
X960959Y-490911D01*
X962706Y-490619D01*
X964889Y-491202D01*
X966417Y-492661D01*
X966854Y-494410D01*
X966636Y-496161D01*
X965762Y-497619D01*
X961396Y-500536D01*
X959431Y-502577D01*
X958121Y-505495D01*
X957684Y-508119D01*
X966854D01*
G01X979769Y-490619D02*
X978022Y-491202D01*
X976712Y-492661D01*
X975839Y-494410D01*
X975184Y-496744D01*
X974966Y-499369D01*
X975184Y-501994D01*
X975839Y-504328D01*
X976712Y-506078D01*
X978022Y-507536D01*
X979769Y-508119D01*
X981515Y-507536D01*
X982826Y-506078D01*
X983699Y-504328D01*
X984354Y-501994D01*
X984572Y-499369D01*
X984354Y-496744D01*
X983699Y-494410D01*
X982826Y-492661D01*
X981515Y-491202D01*
X979769Y-490619D01*
G01X997269Y-508119D02*
Y-490619D01*
X994649Y-494119D01*
G01Y-508119D02*
X999889D01*
G01X1017389D02*
Y-490619D01*
X1009310Y-503161D01*
X1020228D01*
G01X904966Y-463119D02*
Y-445619D01*
X909332D01*
X911079Y-446494D01*
X912389Y-447661D01*
X913481Y-449410D01*
X914354Y-451453D01*
X914572Y-454369D01*
X914354Y-457286D01*
X913481Y-459328D01*
X912389Y-461078D01*
X911079Y-462244D01*
X909332Y-463119D01*
X904966D01*
G01X931199D02*
Y-451453D01*
G01Y-453494D02*
X930326Y-452328D01*
X929015Y-451744D01*
X927487Y-451453D01*
X925959Y-452036D01*
X924649Y-453202D01*
X923775Y-454952D01*
X923339Y-457286D01*
X923775Y-459619D01*
X924649Y-461369D01*
X925959Y-462536D01*
X927487Y-463119D01*
X929015Y-462827D01*
X930326Y-461953D01*
X931199Y-460786D01*
G01X944769Y-445619D02*
Y-463119D01*
G01X941712Y-451453D02*
X947826D01*
G01X958994Y-455244D02*
X965981D01*
X965326Y-453202D01*
X964234Y-452036D01*
X962706Y-451453D01*
X961177Y-451744D01*
X959867Y-452619D01*
X958994Y-454661D01*
X958557Y-456411D01*
Y-458161D01*
X958994Y-459911D01*
X960086Y-461661D01*
X961396Y-462827D01*
X962924Y-463119D01*
X964452Y-462536D01*
X965981Y-460786D01*
G54D39*
X313029Y219500D03*
X310829D03*
X313029Y222500D03*
X310829D03*
X359029Y128500D03*
X356829D03*
X359029Y124500D03*
X356829D03*
X362329Y146000D03*
X361329Y139500D03*
X365600Y134500D03*
X363400D03*
X365529Y131500D03*
X363329D03*
X364529Y146000D03*
X363529Y139500D03*
X391609Y148420D03*
X389409D03*
X415705Y346250D03*
X413505D03*
X444955Y326500D03*
X439855Y327200D03*
X437655D03*
X434055Y359370D03*
X431855D03*
X434100Y372000D03*
X431900D03*
X439755Y374700D03*
X437555D03*
X447155Y326500D03*
X453155Y342000D03*
X450955D03*
X461155Y404000D03*
X458955D03*
X467155Y326500D03*
X464955D03*
X477155Y338500D03*
X474955D03*
X476455Y344500D03*
X473655Y404000D03*
X471455D03*
X474655Y410000D03*
X472455D03*
X478655Y344500D03*
G54D66*
X641625Y458750D03*
X654875Y434750D03*
X647125D03*
X651000Y442250D03*
X645500Y466250D03*
X649375Y458750D03*
G54D57*
X455278Y846000D03*
G54D75*
X1066929Y43267D03*
X1057086D03*
X1084646D03*
X1074803D03*
G54D48*
X357940Y135500D03*
X360140D03*
X354440Y146000D03*
X356640D03*
X355940Y155000D03*
X358140D03*
X355940Y162000D03*
X358140D03*
X378229Y158600D03*
X378189Y164630D03*
X383400Y149500D03*
X385600D03*
X396029Y148500D03*
X380429Y158600D03*
X380389Y164630D03*
X401400Y148500D03*
X403600D03*
X406529Y151600D03*
X408729D03*
X398229Y148500D03*
X433155Y348900D03*
X435355D03*
X441055Y362700D03*
X443255D03*
X441055Y360400D03*
X443255D03*
X437155Y372000D03*
X439355D03*
X437055Y383900D03*
X439255D03*
X437055Y386300D03*
X439255D03*
X451055Y357800D03*
X453255D03*
X477423Y325583D03*
Y327983D03*
X472555Y347300D03*
X474755D03*
X472855Y364900D03*
X475055D03*
X472555Y374800D03*
X474755D03*
X472555Y372500D03*
X474755D03*
X472555Y383800D03*
X474755D03*
X479623Y325583D03*
Y327983D03*
X490455Y371500D03*
X492655D03*
X499255Y344400D03*
X501455D03*
X497455Y380000D03*
X499655D03*
X498955Y393000D03*
X501155D03*
X494955Y405500D03*
X497155D03*
X622640Y417801D03*
X624840D03*
X622640Y413401D03*
X624840D03*
X622640Y431001D03*
X624840D03*
X622640Y426601D03*
X624840D03*
X622640Y422201D03*
X624840D03*
X622640Y435401D03*
X624840D03*
G54D49*
X376000Y10700D03*
X381000D03*
X625500Y348200D03*
X640500D03*
X635500D03*
X630500D03*
X787000Y400700D03*
X1151000Y702200D03*
G54D67*
X670800Y446000D03*
X712548Y117000D03*
X1073300Y140500D03*
X1144768Y695784D03*
X1144800Y700500D03*
X1199250Y698520D03*
X1290300Y433000D03*
X1345300Y394500D03*
X1336317Y533012D03*
Y525012D03*
X1341817Y533012D03*
Y525012D03*
G54D76*
X1224016Y180709D03*
G54D58*
X442278Y846000D03*
X455278D03*
X451278D03*
X459278D03*
X467278D03*
G54D59*
X535000Y134750D03*
X531125Y142250D03*
X538875D03*
G54D68*
X665200Y446000D03*
X706948Y117000D03*
X1067700Y140500D03*
X1139168Y695784D03*
X1139200Y700500D03*
X1193650Y698520D03*
X1284700Y433000D03*
X1330717Y533012D03*
Y525012D03*
X1339700Y394500D03*
X1336217Y533012D03*
Y525012D03*
G54D77*
X1224016Y386221D03*
G54D69*
X673200Y466000D03*
X1341717Y533012D03*
Y525012D03*
G54D78*
X1239500Y671000D03*
G54D79*
X1258504Y329331D03*
Y368701D03*
X1272677Y349016D03*
M02*
